FILE_TYPE = MACRO_DRAWING;
SET COLOR_WIRE YELLOW;
SET COLOR_PROP ORANGE;
SET COLOR_DOT WHITE;
SET COLOR_ARC YELLOW;
SET COLOR_BODY GREEN;
SET COLOR_NOTE PURPLE;
SET PROP_DISPLAY VALUE;
SET PAGE_NUMBER P173;
FORCEADD OFFPAGE..1
(-7850 1875);
FORCEPROP 2 LAST $XR5 199 
J 0
(-8702 1875);
DISPLAY 0.638298 (-8702 1875);
PAINT MONO (-8702 1875);
FORCEPROP 2 LAST $XR0 193 
J 0
(-8102 1875);
DISPLAY 0.638298 (-8102 1875);
PAINT MONO (-8102 1875);
FORCEPROP 2 LAST $XR1 194 
J 0
(-8222 1875);
DISPLAY 0.638298 (-8222 1875);
PAINT MONO (-8222 1875);
FORCEPROP 2 LAST $XR2 195 
J 0
(-8342 1875);
DISPLAY 0.638298 (-8342 1875);
PAINT MONO (-8342 1875);
FORCEPROP 2 LAST $XR3 196 
J 0
(-8462 1875);
DISPLAY 0.638298 (-8462 1875);
PAINT MONO (-8462 1875);
FORCEPROP 2 LAST $XR4 198 
J 0
(-8582 1875);
DISPLAY 0.638298 (-8582 1875);
PAINT MONO (-8582 1875);
FORCEPROP 2 LAST PATH I1
J 0
(-8125 1925);
DISPLAY 0.680851 (-8125 1925);
DISPLAY INVISIBLE (-8125 1925);
FORCEPROP 1 LAST COMMENT_BODY TRUE
J 0
(-7725 1775);
DISPLAY 0.872340 (-7725 1775);
PAINT GREEN (-7725 1775);
DISPLAY INVISIBLE (-7725 1775);
FORCEPROP 1 LAST OFFPAGE TRUE
J 0
(-7525 1750);
DISPLAY 0.872340 (-7525 1750);
PAINT GREEN (-7525 1750);
DISPLAY INVISIBLE (-7525 1750);
FORCEPROP 2 LAST CDS_LIB standard
J 0
(-7850 1875);
DISPLAY INVISIBLE (-7850 1875);
FORCEADD OFFPAGE..2
R 2
(-6950 1975);
FORCEPROP 2 LAST $XR0 193 
J 0
(-7235 1975);
DISPLAY 0.638298 (-7235 1975);
PAINT MONO (-7235 1975);
FORCEPROP 2 LAST PATH I10
J 0
(-7200 2025);
DISPLAY 0.680851 (-7200 2025);
DISPLAY INVISIBLE (-7200 2025);
FORCEPROP 1 LAST COMMENT_BODY TRUE
J 2
(-6905 1880);
DISPLAY 0.872340 (-6905 1880);
PAINT GREEN (-6905 1880);
DISPLAY INVISIBLE (-6905 1880);
FORCEPROP 1 LAST OFFPAGE TRUE
J 2
(-7275 1850);
DISPLAY 0.872340 (-7275 1850);
PAINT GREEN (-7275 1850);
DISPLAY INVISIBLE (-7275 1850);
FORCEPROP 2 LAST CDS_LIB standard
J 2
(-6950 1975);
DISPLAY INVISIBLE (-6950 1975);
FORCEADD Q_CAP..1
(-7300 2325);
FORCEPROP 1 LAST LOCATION PC580
J 0
(-7250 2425);
DISPLAY 0.489362 (-7250 2425);
PAINT SKYBLUE (-7250 2425);
FORCEPROP 0 LAST $SEC 1
J 0
(-7250 2475);
DISPLAY 0.680851 (-7250 2475);
PAINT MONO (-7250 2475);
DISPLAY INVISIBLE (-7250 2475);
FORCEPROP 0 LAST CDS_SEC 1
J 0
(-7250 2475);
DISPLAY 1.021277 (-7250 2475);
DISPLAY INVISIBLE (-7250 2475);
FORCEPROP 1 LASTPIN (-7300 2425) $PN 1
J 0
(-7290 2405);
DISPLAY 0.489362 (-7290 2405);
PAINT MONO (-7290 2405);
FORCEPROP 1 LASTPIN (-7300 2225) $PN 2
J 0
(-7290 2205);
DISPLAY 0.489362 (-7290 2205);
PAINT MONO (-7290 2205);
FORCEPROP 1 LAST PACK_TYPE C0402
J 0
(-7250 2125);
DISPLAY 0.489362 (-7250 2125);
PAINT SKYBLUE (-7250 2125);
FORCEPROP 1 LAST VALUE 2.2UF
J 0
(-7250 2375);
DISPLAY 0.489362 (-7250 2375);
PAINT SKYBLUE (-7250 2375);
FORCEPROP 1 LAST VOLTAGE 10V
J 0
(-7250 2325);
DISPLAY 0.489362 (-7250 2325);
PAINT SKYBLUE (-7250 2325);
FORCEPROP 1 LAST TOLERANCE 10%
J 0
(-7250 2275);
DISPLAY 0.489362 (-7250 2275);
PAINT SKYBLUE (-7250 2275);
FORCEPROP 1 LAST MATERIAL X6S
J 0
(-7250 2225);
DISPLAY 0.489362 (-7250 2225);
PAINT SKYBLUE (-7250 2225);
FORCEPROP 1 LAST PART_NUMBER CH5222KEB01
J 0
(-7250 2175);
DISPLAY 0.489362 (-7250 2175);
PAINT SKYBLUE (-7250 2175);
DISPLAY INVISIBLE (-7250 2175);
FORCEPROP 1 LAST PATH I11
J 0
(-7250 2475);
DISPLAY 0.978723 (-7250 2475);
PAINT WHITE (-7250 2475);
DISPLAY INVISIBLE (-7250 2475);
FORCEPROP 2 LAST CDS_LIB pure_quanta
J 0
(-7300 2325);
DISPLAY INVISIBLE (-7300 2325);
FORCEADD Q_RES..2
(-7300 2850);
FORCEPROP 1 LAST LOCATION PR357
J 0
(-7255 2975);
DISPLAY 0.489362 (-7255 2975);
PAINT SKYBLUE (-7255 2975);
FORCEPROP 0 LAST $SEC 1
J 0
(-7250 3025);
DISPLAY 0.680851 (-7250 3025);
PAINT MONO (-7250 3025);
DISPLAY INVISIBLE (-7250 3025);
FORCEPROP 0 LAST CDS_SEC 1
J 0
(-7250 3025);
DISPLAY 1.021277 (-7250 3025);
DISPLAY INVISIBLE (-7250 3025);
FORCEPROP 1 LASTPIN (-7300 2950) $PN 1
J 0
(-7295 2912);
DISPLAY 0.489362 (-7295 2912);
PAINT MONO (-7295 2912);
FORCEPROP 1 LASTPIN (-7300 2750) $PN 2
J 0
(-7295 2760);
DISPLAY 0.489362 (-7295 2760);
PAINT MONO (-7295 2760);
FORCEPROP 1 LAST WATTAGE 1/16W
J 0
(-7250 2825);
DISPLAY 0.489362 (-7250 2825);
PAINT SKYBLUE (-7250 2825);
FORCEPROP 1 LAST MATERIAL CHIP
J 0
(-7250 2775);
DISPLAY 0.489362 (-7250 2775);
PAINT SKYBLUE (-7250 2775);
FORCEPROP 1 LAST TOLERANCE 1%
J 0
(-7250 2875);
DISPLAY 0.489362 (-7250 2875);
PAINT SKYBLUE (-7250 2875);
FORCEPROP 1 LAST VALUE 2.2
J 0
(-7250 2925);
DISPLAY 0.489362 (-7250 2925);
PAINT SKYBLUE (-7250 2925);
FORCEPROP 1 LAST PACK_TYPE 0402LF
J 0
(-7250 2675);
DISPLAY 0.489362 (-7250 2675);
PAINT SKYBLUE (-7250 2675);
FORCEPROP 1 LAST PART_NUMBER CS-2202FB01
J 0
(-7250 2725);
DISPLAY 0.489362 (-7250 2725);
PAINT SKYBLUE (-7250 2725);
DISPLAY INVISIBLE (-7250 2725);
FORCEPROP 1 LAST PATH I12
J 0
(-7250 3025);
DISPLAY 0.978723 (-7250 3025);
PAINT WHITE (-7250 3025);
DISPLAY INVISIBLE (-7250 3025);
FORCEPROP 2 LAST CDS_LIB pure_quanta
J 0
(-7300 2850);
DISPLAY INVISIBLE (-7300 2850);
FORCEADD VCC_CORE..1
(-7300 3250);
FORCEPROP 3 LASTPIN (-7300 3200) SIG_NAME PVDDCR_CPU0_P0_PVCC\g
J 0
(-7290 3210);
DISPLAY 0.659574 (-7290 3210);
PAINT MONO (-7290 3210);
DISPLAY INVISIBLE (-7290 3210);
FORCEPROP 1 LAST HDL_POWER PVDDCR_CPU0_P0_PVCC
J 1
(-7300 3300);
DISPLAY 0.489362 (-7300 3300);
PAINT GREEN (-7300 3300);
FORCEPROP 1 LAST PATH I13
J 0
(-7250 3275);
DISPLAY 0.872340 (-7250 3275);
PAINT AQUA (-7250 3275);
DISPLAY INVISIBLE (-7250 3275);
FORCEPROP 2 LAST CDS_LIB pure_quanta_power
J 0
(-7300 3250);
DISPLAY INVISIBLE (-7300 3250);
FORCEADD Q_CAP..1
(-6950 2850);
FORCEPROP 1 LAST LOCATION PC582_SOP0_2
J 0
(-6900 2950);
DISPLAY 0.489362 (-6900 2950);
PAINT SKYBLUE (-6900 2950);
FORCEPROP 0 LAST $SEC 1
J 0
(-6900 3000);
DISPLAY 0.680851 (-6900 3000);
PAINT MONO (-6900 3000);
DISPLAY INVISIBLE (-6900 3000);
FORCEPROP 0 LAST CDS_SEC 1
J 0
(-6900 3000);
DISPLAY 1.021277 (-6900 3000);
DISPLAY INVISIBLE (-6900 3000);
FORCEPROP 1 LASTPIN (-6950 2950) $PN 1
J 0
(-6940 2930);
DISPLAY 0.489362 (-6940 2930);
PAINT MONO (-6940 2930);
FORCEPROP 1 LASTPIN (-6950 2750) $PN 2
J 0
(-6940 2730);
DISPLAY 0.489362 (-6940 2730);
PAINT MONO (-6940 2730);
FORCEPROP 1 LAST TOLERANCE 10%
J 0
(-6900 2800);
DISPLAY 0.489362 (-6900 2800);
PAINT SKYBLUE (-6900 2800);
FORCEPROP 1 LAST MATERIAL X6S
J 0
(-6900 2750);
DISPLAY 0.489362 (-6900 2750);
PAINT SKYBLUE (-6900 2750);
FORCEPROP 1 LAST PACK_TYPE C0402
J 0
(-6900 2650);
DISPLAY 0.489362 (-6900 2650);
PAINT SKYBLUE (-6900 2650);
FORCEPROP 1 LAST VOLTAGE 10V
J 0
(-6900 2850);
DISPLAY 0.489362 (-6900 2850);
PAINT SKYBLUE (-6900 2850);
FORCEPROP 1 LAST VALUE 2.2UF
J 0
(-6900 2900);
DISPLAY 0.489362 (-6900 2900);
PAINT SKYBLUE (-6900 2900);
FORCEPROP 1 LAST PART_NUMBER CH5222KEB01
J 0
(-6900 2700);
DISPLAY 0.489362 (-6900 2700);
PAINT SKYBLUE (-6900 2700);
DISPLAY INVISIBLE (-6900 2700);
FORCEPROP 1 LAST PATH I14
J 0
(-6900 3000);
DISPLAY 0.978723 (-6900 3000);
PAINT WHITE (-6900 3000);
DISPLAY INVISIBLE (-6900 3000);
FORCEPROP 2 LAST CDS_LIB pure_quanta
J 0
(-6950 2850);
DISPLAY INVISIBLE (-6950 2850);
FORCEADD UNIVERSAL_GND..1
(-6950 2600);
FORCEPROP 3 LASTPIN (-6950 2650) SIG_NAME GND\g
J 0
(-6940 2660);
DISPLAY 0.659574 (-6940 2660);
PAINT MONO (-6940 2660);
DISPLAY INVISIBLE (-6940 2660);
FORCEPROP 1 LAST PATH I15
J 0
(-6875 2600);
DISPLAY 0.872340 (-6875 2600);
PAINT AQUA (-6875 2600);
DISPLAY INVISIBLE (-6875 2600);
FORCEPROP 1 LAST HDL_POWER GND
J 1
(-6925 2525);
DISPLAY 0.872340 (-6925 2525);
PAINT GREEN (-6925 2525);
DISPLAY INVISIBLE (-6925 2525);
FORCEPROP 2 LAST CDS_LIB pure_quanta_power
J 0
(-6950 2600);
DISPLAY INVISIBLE (-6950 2600);
FORCEADD UNIVERSAL_GND..1
(-5225 1275);
FORCEPROP 3 LASTPIN (-5225 1325) SIG_NAME GND\g
J 0
(-5215 1335);
DISPLAY 0.659574 (-5215 1335);
PAINT MONO (-5215 1335);
DISPLAY INVISIBLE (-5215 1335);
FORCEPROP 1 LAST PATH I16
J 0
(-5150 1275);
DISPLAY 0.872340 (-5150 1275);
PAINT AQUA (-5150 1275);
DISPLAY INVISIBLE (-5150 1275);
FORCEPROP 1 LAST HDL_POWER GND
J 1
(-5200 1200);
DISPLAY 0.872340 (-5200 1200);
PAINT GREEN (-5200 1200);
DISPLAY INVISIBLE (-5200 1200);
FORCEPROP 2 LAST CDS_LIB pure_quanta_power
J 0
(-5225 1275);
DISPLAY INVISIBLE (-5225 1275);
FORCEADD UNIVERSAL_GND..1
(-4500 1075);
FORCEPROP 3 LASTPIN (-4500 1125) SIG_NAME GND\g
J 0
(-4490 1135);
DISPLAY 0.659574 (-4490 1135);
PAINT MONO (-4490 1135);
DISPLAY INVISIBLE (-4490 1135);
FORCEPROP 1 LAST PATH I17
J 0
(-4425 1075);
DISPLAY 0.872340 (-4425 1075);
PAINT AQUA (-4425 1075);
DISPLAY INVISIBLE (-4425 1075);
FORCEPROP 1 LAST HDL_POWER GND
J 1
(-4475 1000);
DISPLAY 0.872340 (-4475 1000);
PAINT GREEN (-4475 1000);
DISPLAY INVISIBLE (-4475 1000);
FORCEPROP 2 LAST CDS_LIB pure_quanta_power
J 0
(-4500 1075);
DISPLAY INVISIBLE (-4500 1075);
FORCEADD Q_RES..1
(-4025 975);
FORCEPROP 1 LAST LOCATION PR363
J 0
(-4050 1025);
DISPLAY 0.489362 (-4050 1025);
PAINT SKYBLUE (-4050 1025);
FORCEPROP 0 LAST $SEC 1
J 0
(-4025 1050);
DISPLAY 0.680851 (-4025 1050);
PAINT MONO (-4025 1050);
DISPLAY INVISIBLE (-4025 1050);
FORCEPROP 0 LAST CDS_SEC 1
J 0
(-4025 1050);
DISPLAY 1.021277 (-4025 1050);
DISPLAY INVISIBLE (-4025 1050);
FORCEPROP 1 LASTPIN (-4125 975) $PN 1
J 0
(-4113 987);
DISPLAY 0.489362 (-4113 987);
PAINT MONO (-4113 987);
FORCEPROP 1 LASTPIN (-3925 975) $PN 2
J 0
(-3963 987);
DISPLAY 0.489362 (-3963 987);
PAINT MONO (-3963 987);
FORCEPROP 1 LAST WATTAGE 1/16W
J 0
(-3925 925);
DISPLAY 0.489362 (-3925 925);
PAINT SKYBLUE (-3925 925);
FORCEPROP 1 LAST TOLERANCE 5%
J 0
(-3900 1000);
DISPLAY 0.489362 (-3900 1000);
PAINT SKYBLUE (-3900 1000);
FORCEPROP 1 LAST MATERIAL CHIP
J 0
(-4275 875);
DISPLAY 0.489362 (-4275 875);
PAINT SKYBLUE (-4275 875);
FORCEPROP 1 LAST VALUE 0
J 2
(-4150 1000);
DISPLAY 0.489362 (-4150 1000);
PAINT SKYBLUE (-4150 1000);
FORCEPROP 1 LAST PACK_TYPE 0402LF
J 0
(-3925 875);
DISPLAY 0.489362 (-3925 875);
PAINT SKYBLUE (-3925 875);
FORCEPROP 1 LAST PART_NUMBER CS00002JB13
J 0
(-4275 925);
DISPLAY 0.489362 (-4275 925);
PAINT SKYBLUE (-4275 925);
DISPLAY INVISIBLE (-4275 925);
FORCEPROP 1 LAST PATH I18
J 0
(-4075 1125);
DISPLAY 0.978723 (-4075 1125);
PAINT WHITE (-4075 1125);
DISPLAY INVISIBLE (-4075 1125);
FORCEPROP 2 LAST CDS_LIB pure_quanta
J 0
(-4025 975);
DISPLAY INVISIBLE (-4025 975);
FORCEADD Q_RES..2
(-4500 1300);
FORCEPROP 1 LAST LOCATION PR503
J 0
(-4455 1425);
DISPLAY 0.489362 (-4455 1425);
PAINT SKYBLUE (-4455 1425);
FORCEPROP 0 LAST $SEC 1
J 0
(-4450 1475);
DISPLAY 0.680851 (-4450 1475);
PAINT MONO (-4450 1475);
DISPLAY INVISIBLE (-4450 1475);
FORCEPROP 0 LAST CDS_SEC 1
J 0
(-4450 1475);
DISPLAY 1.021277 (-4450 1475);
DISPLAY INVISIBLE (-4450 1475);
FORCEPROP 1 LASTPIN (-4500 1400) $PN 1
J 0
(-4495 1362);
DISPLAY 0.489362 (-4495 1362);
PAINT MONO (-4495 1362);
FORCEPROP 1 LASTPIN (-4500 1200) $PN 2
J 0
(-4495 1210);
DISPLAY 0.489362 (-4495 1210);
PAINT MONO (-4495 1210);
FORCEPROP 1 LAST PACK_TYPE 0402LF
J 0
(-4460 1125);
DISPLAY 0.489362 (-4460 1125);
PAINT SKYBLUE (-4460 1125);
FORCEPROP 1 LAST VALUE 1.5
J 0
(-4455 1375);
DISPLAY 0.489362 (-4455 1375);
PAINT SKYBLUE (-4455 1375);
FORCEPROP 1 LAST TOLERANCE 1%
J 0
(-4455 1325);
DISPLAY 0.489362 (-4455 1325);
PAINT SKYBLUE (-4455 1325);
FORCEPROP 1 LAST MATERIAL EMPTY
J 0
(-4460 1225);
DISPLAY 0.489362 (-4460 1225);
PAINT RED (-4460 1225);
FORCEPROP 1 LAST WATTAGE 1/8W
J 0
(-4460 1275);
DISPLAY 0.489362 (-4460 1275);
PAINT SKYBLUE (-4460 1275);
FORCEPROP 1 LAST PART_NUMBER CS-1504FB00
J 0
(-4460 1175);
DISPLAY 0.489362 (-4460 1175);
PAINT SKYBLUE (-4460 1175);
DISPLAY INVISIBLE (-4460 1175);
FORCEPROP 1 LAST PATH I19
J 0
(-4450 1475);
DISPLAY 0.978723 (-4450 1475);
PAINT WHITE (-4450 1475);
DISPLAY INVISIBLE (-4450 1475);
FORCEPROP 2 LAST CDS_LIB pure_quanta
J 0
(-4500 1300);
DISPLAY INVISIBLE (-4500 1300);
FORCEADD OFFPAGE..1
(-7875 4975);
FORCEPROP 2 LAST $XR0 193 
J 0
(-8127 4975);
DISPLAY 0.638298 (-8127 4975);
PAINT MONO (-8127 4975);
FORCEPROP 2 LAST $XR1 194 
J 0
(-8247 4975);
DISPLAY 0.638298 (-8247 4975);
PAINT MONO (-8247 4975);
FORCEPROP 2 LAST $XR2 195 
J 0
(-8367 4975);
DISPLAY 0.638298 (-8367 4975);
PAINT MONO (-8367 4975);
FORCEPROP 2 LAST $XR3 196 
J 0
(-8487 4975);
DISPLAY 0.638298 (-8487 4975);
PAINT MONO (-8487 4975);
FORCEPROP 2 LAST $XR4 198 
J 0
(-8607 4975);
DISPLAY 0.638298 (-8607 4975);
PAINT MONO (-8607 4975);
FORCEPROP 2 LAST $XR5 199 
J 0
(-8727 4975);
DISPLAY 0.638298 (-8727 4975);
PAINT MONO (-8727 4975);
FORCEPROP 2 LAST PATH I2
J 0
(-8125 5025);
DISPLAY 0.680851 (-8125 5025);
DISPLAY INVISIBLE (-8125 5025);
FORCEPROP 1 LAST COMMENT_BODY TRUE
J 0
(-7750 4875);
DISPLAY 0.872340 (-7750 4875);
PAINT GREEN (-7750 4875);
DISPLAY INVISIBLE (-7750 4875);
FORCEPROP 1 LAST OFFPAGE TRUE
J 0
(-7550 4850);
DISPLAY 0.872340 (-7550 4850);
PAINT GREEN (-7550 4850);
DISPLAY INVISIBLE (-7550 4850);
FORCEPROP 2 LAST CDS_LIB standard
J 0
(-7875 4975);
DISPLAY INVISIBLE (-7875 4975);
FORCEADD OFFPAGE..3
R 2
(-3800 1725);
FORCEPROP 2 LAST $XR0 199 
J 0
(-4080 1725);
DISPLAY 0.638298 (-4080 1725);
PAINT MONO (-4080 1725);
FORCEPROP 2 LAST PATH I20
J 0
(-4100 1775);
DISPLAY 0.680851 (-4100 1775);
DISPLAY INVISIBLE (-4100 1775);
FORCEPROP 1 LAST COMMENT_BODY TRUE
J 2
(-3750 1625);
DISPLAY 0.872340 (-3750 1625);
PAINT GREEN (-3750 1625);
DISPLAY INVISIBLE (-3750 1625);
FORCEPROP 1 LAST OFFPAGE TRUE
J 2
(-4125 1600);
DISPLAY 0.872340 (-4125 1600);
PAINT GREEN (-4125 1600);
DISPLAY INVISIBLE (-4125 1600);
FORCEPROP 2 LAST CDS_LIB standard
J 2
(-3800 1725);
DISPLAY INVISIBLE (-3800 1725);
FORCEADD Q_CAP..1
(-5150 2875);
FORCEPROP 1 LAST LOCATION PC586_2
J 0
(-5100 2975);
DISPLAY 0.489362 (-5100 2975);
PAINT SKYBLUE (-5100 2975);
FORCEPROP 0 LAST $SEC 1
J 0
(-5100 3025);
DISPLAY 0.680851 (-5100 3025);
PAINT MONO (-5100 3025);
DISPLAY INVISIBLE (-5100 3025);
FORCEPROP 0 LAST CDS_SEC 1
J 0
(-5100 3025);
DISPLAY 1.021277 (-5100 3025);
DISPLAY INVISIBLE (-5100 3025);
FORCEPROP 1 LASTPIN (-5150 2975) $PN 1
J 0
(-5140 2955);
DISPLAY 0.489362 (-5140 2955);
PAINT MONO (-5140 2955);
FORCEPROP 1 LASTPIN (-5150 2775) $PN 2
J 0
(-5140 2755);
DISPLAY 0.489362 (-5140 2755);
PAINT MONO (-5140 2755);
FORCEPROP 1 LAST MATERIAL X7R
J 0
(-5100 2775);
DISPLAY 0.489362 (-5100 2775);
PAINT SKYBLUE (-5100 2775);
FORCEPROP 1 LAST TOLERANCE 10%
J 0
(-5100 2825);
DISPLAY 0.489362 (-5100 2825);
PAINT SKYBLUE (-5100 2825);
FORCEPROP 1 LAST PACK_TYPE 0402
J 0
(-5100 2675);
DISPLAY 0.489362 (-5100 2675);
PAINT SKYBLUE (-5100 2675);
FORCEPROP 1 LAST VOLTAGE 25V
J 0
(-5100 2875);
DISPLAY 0.489362 (-5100 2875);
PAINT SKYBLUE (-5100 2875);
FORCEPROP 1 LAST VALUE 0.1UF
J 0
(-5100 2925);
DISPLAY 0.489362 (-5100 2925);
PAINT SKYBLUE (-5100 2925);
FORCEPROP 1 LAST PART_NUMBER CH4104K1B00
J 0
(-5100 2725);
DISPLAY 0.489362 (-5100 2725);
PAINT SKYBLUE (-5100 2725);
DISPLAY INVISIBLE (-5100 2725);
FORCEPROP 1 LAST PATH I21
J 0
(-5100 3025);
DISPLAY 0.978723 (-5100 3025);
PAINT WHITE (-5100 3025);
DISPLAY INVISIBLE (-5100 3025);
FORCEPROP 2 LAST CDS_LIB pure_quanta
J 0
(-5150 2875);
DISPLAY INVISIBLE (-5150 2875);
FORCEADD Q_RES..1
(-4475 2325);
FORCEPROP 1 LAST LOCATION PR361
J 0
(-4500 2375);
DISPLAY 0.489362 (-4500 2375);
PAINT SKYBLUE (-4500 2375);
FORCEPROP 0 LAST $SEC 1
J 0
(-4450 2400);
DISPLAY 0.680851 (-4450 2400);
PAINT MONO (-4450 2400);
DISPLAY INVISIBLE (-4450 2400);
FORCEPROP 0 LAST CDS_SEC 1
J 0
(-4450 2400);
DISPLAY 1.021277 (-4450 2400);
DISPLAY INVISIBLE (-4450 2400);
FORCEPROP 1 LASTPIN (-4575 2325) $PN 1
J 0
(-4563 2337);
DISPLAY 0.489362 (-4563 2337);
PAINT MONO (-4563 2337);
FORCEPROP 1 LASTPIN (-4375 2325) $PN 2
J 0
(-4413 2337);
DISPLAY 0.489362 (-4413 2337);
PAINT MONO (-4413 2337);
FORCEPROP 1 LAST TOLERANCE 1%
J 0
(-4350 2350);
DISPLAY 0.489362 (-4350 2350);
PAINT SKYBLUE (-4350 2350);
FORCEPROP 1 LAST PACK_TYPE 0402LF
J 0
(-4375 2225);
DISPLAY 0.489362 (-4375 2225);
PAINT SKYBLUE (-4375 2225);
FORCEPROP 1 LAST WATTAGE 1/16W
J 0
(-4375 2275);
DISPLAY 0.489362 (-4375 2275);
PAINT SKYBLUE (-4375 2275);
FORCEPROP 1 LAST MATERIAL CHIP
J 0
(-4725 2225);
DISPLAY 0.489362 (-4725 2225);
PAINT SKYBLUE (-4725 2225);
FORCEPROP 1 LAST VALUE 5.6
J 2
(-4600 2350);
DISPLAY 0.489362 (-4600 2350);
PAINT SKYBLUE (-4600 2350);
FORCEPROP 1 LAST PART_NUMBER CS-5602FB01
J 0
(-4725 2275);
DISPLAY 0.489362 (-4725 2275);
PAINT SKYBLUE (-4725 2275);
DISPLAY INVISIBLE (-4725 2275);
FORCEPROP 1 LAST PATH I22
J 0
(-4525 2475);
DISPLAY 0.978723 (-4525 2475);
PAINT WHITE (-4525 2475);
DISPLAY INVISIBLE (-4525 2475);
FORCEPROP 2 LAST CDS_LIB pure_quanta
J 0
(-4475 2325);
DISPLAY INVISIBLE (-4475 2325);
FORCEADD Q_CAP..1
(-4775 2875);
FORCEPROP 1 LAST LOCATION PC584_2
J 0
(-4725 2975);
DISPLAY 0.489362 (-4725 2975);
PAINT SKYBLUE (-4725 2975);
FORCEPROP 0 LAST $SEC 1
J 0
(-4725 3000);
DISPLAY 0.680851 (-4725 3000);
PAINT MONO (-4725 3000);
DISPLAY INVISIBLE (-4725 3000);
FORCEPROP 0 LAST CDS_SEC 1
J 0
(-4725 3000);
DISPLAY 1.021277 (-4725 3000);
DISPLAY INVISIBLE (-4725 3000);
FORCEPROP 1 LASTPIN (-4775 2975) $PN 1
J 0
(-4765 2955);
DISPLAY 0.489362 (-4765 2955);
PAINT MONO (-4765 2955);
FORCEPROP 1 LASTPIN (-4775 2775) $PN 2
J 0
(-4765 2755);
DISPLAY 0.489362 (-4765 2755);
PAINT MONO (-4765 2755);
FORCEPROP 1 LAST VOLTAGE 25V
J 0
(-4725 2875);
DISPLAY 0.489362 (-4725 2875);
PAINT SKYBLUE (-4725 2875);
FORCEPROP 1 LAST PACK_TYPE C0402
J 0
(-4725 2675);
DISPLAY 0.489362 (-4725 2675);
PAINT SKYBLUE (-4725 2675);
FORCEPROP 1 LAST MATERIAL X6S
J 0
(-4725 2775);
DISPLAY 0.489362 (-4725 2775);
PAINT SKYBLUE (-4725 2775);
FORCEPROP 1 LAST VALUE 1UF
J 0
(-4725 2925);
DISPLAY 0.489362 (-4725 2925);
PAINT SKYBLUE (-4725 2925);
FORCEPROP 1 LAST TOLERANCE 10%
J 0
(-4725 2825);
DISPLAY 0.489362 (-4725 2825);
PAINT SKYBLUE (-4725 2825);
FORCEPROP 1 LAST PART_NUMBER CH5104KEB02
J 0
(-4725 2725);
DISPLAY 0.489362 (-4725 2725);
PAINT SKYBLUE (-4725 2725);
DISPLAY INVISIBLE (-4725 2725);
FORCEPROP 1 LAST PATH I23
J 0
(-4725 3025);
DISPLAY 0.978723 (-4725 3025);
PAINT WHITE (-4725 3025);
DISPLAY INVISIBLE (-4725 3025);
FORCEPROP 2 LAST CDS_LIB pure_quanta
J 0
(-4775 2875);
DISPLAY INVISIBLE (-4775 2875);
FORCEADD Q_CAP..1
(-4450 2875);
FORCEPROP 1 LAST LOCATION PC588_2
J 0
(-4400 2975);
DISPLAY 0.489362 (-4400 2975);
PAINT SKYBLUE (-4400 2975);
FORCEPROP 0 LAST $SEC 1
J 0
(-4400 3000);
DISPLAY 0.680851 (-4400 3000);
PAINT MONO (-4400 3000);
DISPLAY INVISIBLE (-4400 3000);
FORCEPROP 0 LAST CDS_SEC 1
J 0
(-4400 3000);
DISPLAY 1.021277 (-4400 3000);
DISPLAY INVISIBLE (-4400 3000);
FORCEPROP 1 LASTPIN (-4450 2975) $PN 1
J 0
(-4440 2955);
DISPLAY 0.489362 (-4440 2955);
PAINT MONO (-4440 2955);
FORCEPROP 1 LASTPIN (-4450 2775) $PN 2
J 0
(-4440 2755);
DISPLAY 0.489362 (-4440 2755);
PAINT MONO (-4440 2755);
FORCEPROP 1 LAST MATERIAL X6S
J 0
(-4400 2775);
DISPLAY 0.489362 (-4400 2775);
PAINT SKYBLUE (-4400 2775);
FORCEPROP 1 LAST TOLERANCE 20%
J 0
(-4400 2825);
DISPLAY 0.489362 (-4400 2825);
PAINT SKYBLUE (-4400 2825);
FORCEPROP 1 LAST VOLTAGE 16V
J 0
(-4400 2875);
DISPLAY 0.489362 (-4400 2875);
PAINT SKYBLUE (-4400 2875);
FORCEPROP 1 LAST VALUE 22UF
J 0
(-4400 2925);
DISPLAY 0.489362 (-4400 2925);
PAINT SKYBLUE (-4400 2925);
FORCEPROP 1 LAST PACK_TYPE C0805
J 0
(-4400 2675);
DISPLAY 0.489362 (-4400 2675);
PAINT SKYBLUE (-4400 2675);
FORCEPROP 1 LAST PART_NUMBER CH6223MEA01
J 0
(-4400 2725);
DISPLAY 0.489362 (-4400 2725);
PAINT SKYBLUE (-4400 2725);
DISPLAY INVISIBLE (-4400 2725);
FORCEPROP 1 LAST PATH I24
J 0
(-4400 3025);
DISPLAY 0.978723 (-4400 3025);
PAINT WHITE (-4400 3025);
DISPLAY INVISIBLE (-4400 3025);
FORCEPROP 2 LAST CDS_LIB pure_quanta
J 0
(-4450 2875);
DISPLAY INVISIBLE (-4450 2875);
FORCEADD Q_CAP..1
(-4125 2875);
FORCEPROP 1 LAST LOCATION PC590_2
J 0
(-4075 2975);
DISPLAY 0.489362 (-4075 2975);
PAINT SKYBLUE (-4075 2975);
FORCEPROP 0 LAST $SEC 1
J 0
(-4075 3000);
DISPLAY 0.680851 (-4075 3000);
PAINT MONO (-4075 3000);
DISPLAY INVISIBLE (-4075 3000);
FORCEPROP 0 LAST CDS_SEC 1
J 0
(-4075 3000);
DISPLAY 1.021277 (-4075 3000);
DISPLAY INVISIBLE (-4075 3000);
FORCEPROP 1 LASTPIN (-4125 2975) $PN 1
J 0
(-4115 2955);
DISPLAY 0.489362 (-4115 2955);
PAINT MONO (-4115 2955);
FORCEPROP 1 LASTPIN (-4125 2775) $PN 2
J 0
(-4115 2755);
DISPLAY 0.489362 (-4115 2755);
PAINT MONO (-4115 2755);
FORCEPROP 1 LAST VOLTAGE 16V
J 0
(-4075 2875);
DISPLAY 0.489362 (-4075 2875);
PAINT SKYBLUE (-4075 2875);
FORCEPROP 1 LAST TOLERANCE 20%
J 0
(-4075 2825);
DISPLAY 0.489362 (-4075 2825);
PAINT SKYBLUE (-4075 2825);
FORCEPROP 1 LAST MATERIAL X6S
J 0
(-4075 2775);
DISPLAY 0.489362 (-4075 2775);
PAINT SKYBLUE (-4075 2775);
FORCEPROP 1 LAST PACK_TYPE C0805
J 0
(-4075 2675);
DISPLAY 0.489362 (-4075 2675);
PAINT SKYBLUE (-4075 2675);
FORCEPROP 1 LAST VALUE 22UF
J 0
(-4075 2925);
DISPLAY 0.489362 (-4075 2925);
PAINT SKYBLUE (-4075 2925);
FORCEPROP 1 LAST PART_NUMBER CH6223MEA01
J 0
(-4075 2725);
DISPLAY 0.489362 (-4075 2725);
PAINT SKYBLUE (-4075 2725);
DISPLAY INVISIBLE (-4075 2725);
FORCEPROP 1 LAST PATH I25
J 0
(-4075 3025);
DISPLAY 0.978723 (-4075 3025);
PAINT WHITE (-4075 3025);
DISPLAY INVISIBLE (-4075 3025);
FORCEPROP 2 LAST CDS_LIB pure_quanta
J 0
(-4125 2875);
DISPLAY INVISIBLE (-4125 2875);
FORCEADD UNIVERSAL_GND..1
(-4475 4125);
FORCEPROP 3 LASTPIN (-4475 4175) SIG_NAME GND\g
J 0
(-4465 4185);
DISPLAY 0.659574 (-4465 4185);
PAINT MONO (-4465 4185);
DISPLAY INVISIBLE (-4465 4185);
FORCEPROP 1 LAST PATH I26
J 0
(-4400 4125);
DISPLAY 0.872340 (-4400 4125);
PAINT AQUA (-4400 4125);
DISPLAY INVISIBLE (-4400 4125);
FORCEPROP 1 LAST HDL_POWER GND
J 1
(-4450 4050);
DISPLAY 0.872340 (-4450 4050);
PAINT GREEN (-4450 4050);
DISPLAY INVISIBLE (-4450 4050);
FORCEPROP 2 LAST CDS_LIB pure_quanta_power
J 0
(-4475 4125);
DISPLAY INVISIBLE (-4475 4125);
FORCEADD Q_RES..1
(-4000 3900);
FORCEPROP 1 LAST LOCATION PR362
J 0
(-4050 3950);
DISPLAY 0.489362 (-4050 3950);
PAINT SKYBLUE (-4050 3950);
FORCEPROP 0 LAST $SEC 1
J 0
(-4000 3975);
DISPLAY 0.680851 (-4000 3975);
PAINT MONO (-4000 3975);
DISPLAY INVISIBLE (-4000 3975);
FORCEPROP 0 LAST CDS_SEC 1
J 0
(-4000 3975);
DISPLAY 1.021277 (-4000 3975);
DISPLAY INVISIBLE (-4000 3975);
FORCEPROP 1 LASTPIN (-4100 3900) $PN 1
J 0
(-4088 3912);
DISPLAY 0.489362 (-4088 3912);
PAINT MONO (-4088 3912);
FORCEPROP 1 LASTPIN (-3900 3900) $PN 2
J 0
(-3938 3912);
DISPLAY 0.489362 (-3938 3912);
PAINT MONO (-3938 3912);
FORCEPROP 1 LAST PACK_TYPE 0402LF
J 0
(-3900 3800);
DISPLAY 0.489362 (-3900 3800);
PAINT SKYBLUE (-3900 3800);
FORCEPROP 1 LAST TOLERANCE 5%
J 0
(-3875 3925);
DISPLAY 0.489362 (-3875 3925);
PAINT SKYBLUE (-3875 3925);
FORCEPROP 1 LAST WATTAGE 1/16W
J 0
(-3900 3850);
DISPLAY 0.489362 (-3900 3850);
PAINT SKYBLUE (-3900 3850);
FORCEPROP 1 LAST MATERIAL CHIP
J 0
(-4250 3800);
DISPLAY 0.489362 (-4250 3800);
PAINT SKYBLUE (-4250 3800);
FORCEPROP 1 LAST VALUE 0
J 2
(-4125 3925);
DISPLAY 0.489362 (-4125 3925);
PAINT SKYBLUE (-4125 3925);
FORCEPROP 1 LAST PART_NUMBER CS00002JB13
J 0
(-4250 3850);
DISPLAY 0.489362 (-4250 3850);
PAINT SKYBLUE (-4250 3850);
DISPLAY INVISIBLE (-4250 3850);
FORCEPROP 1 LAST PATH I27
J 0
(-4050 4050);
DISPLAY 0.978723 (-4050 4050);
PAINT WHITE (-4050 4050);
DISPLAY INVISIBLE (-4050 4050);
FORCEPROP 2 LAST CDS_LIB pure_quanta
J 0
(-4000 3900);
DISPLAY INVISIBLE (-4000 3900);
FORCEADD UNIVERSAL_GND..1
(-7650 4525);
FORCEPROP 3 LASTPIN (-7650 4575) SIG_NAME GND\g
J 0
(-7640 4585);
DISPLAY 0.659574 (-7640 4585);
PAINT MONO (-7640 4585);
DISPLAY INVISIBLE (-7640 4585);
FORCEPROP 1 LAST PATH I28
J 0
(-7575 4525);
DISPLAY 0.872340 (-7575 4525);
PAINT AQUA (-7575 4525);
DISPLAY INVISIBLE (-7575 4525);
FORCEPROP 1 LAST HDL_POWER GND
J 1
(-7625 4450);
DISPLAY 0.872340 (-7625 4450);
PAINT GREEN (-7625 4450);
DISPLAY INVISIBLE (-7625 4450);
FORCEPROP 2 LAST CDS_LIB pure_quanta_power
J 0
(-7650 4525);
DISPLAY INVISIBLE (-7650 4525);
FORCEADD Q_CAP..1
(-7650 4800);
FORCEPROP 1 LAST LOCATION PC577_7
J 0
(-7600 4900);
DISPLAY 0.489362 (-7600 4900);
PAINT SKYBLUE (-7600 4900);
FORCEPROP 0 LAST $SEC 1
J 0
(-7600 4925);
DISPLAY 0.680851 (-7600 4925);
PAINT MONO (-7600 4925);
DISPLAY INVISIBLE (-7600 4925);
FORCEPROP 0 LAST CDS_SEC 1
J 0
(-7600 4925);
DISPLAY 1.021277 (-7600 4925);
DISPLAY INVISIBLE (-7600 4925);
FORCEPROP 1 LASTPIN (-7650 4900) $PN 1
J 0
(-7640 4880);
DISPLAY 0.489362 (-7640 4880);
PAINT MONO (-7640 4880);
FORCEPROP 1 LASTPIN (-7650 4700) $PN 2
J 0
(-7640 4680);
DISPLAY 0.489362 (-7640 4680);
PAINT MONO (-7640 4680);
FORCEPROP 1 LAST VOLTAGE 25V
J 0
(-7600 4800);
DISPLAY 0.489362 (-7600 4800);
PAINT SKYBLUE (-7600 4800);
FORCEPROP 1 LAST PACK_TYPE 0402
J 0
(-7600 4600);
DISPLAY 0.489362 (-7600 4600);
PAINT SKYBLUE (-7600 4600);
FORCEPROP 1 LAST MATERIAL X7R
J 0
(-7600 4700);
DISPLAY 0.489362 (-7600 4700);
PAINT SKYBLUE (-7600 4700);
FORCEPROP 1 LAST TOLERANCE 10%
J 0
(-7600 4750);
DISPLAY 0.489362 (-7600 4750);
PAINT SKYBLUE (-7600 4750);
FORCEPROP 1 LAST VALUE 0.1UF
J 0
(-7600 4850);
DISPLAY 0.489362 (-7600 4850);
PAINT SKYBLUE (-7600 4850);
FORCEPROP 1 LAST PART_NUMBER CH4104K1B00
J 0
(-7600 4650);
DISPLAY 0.489362 (-7600 4650);
PAINT SKYBLUE (-7600 4650);
DISPLAY INVISIBLE (-7600 4650);
FORCEPROP 1 LAST PATH I29
J 0
(-7600 4950);
DISPLAY 0.978723 (-7600 4950);
PAINT WHITE (-7600 4950);
DISPLAY INVISIBLE (-7600 4950);
FORCEPROP 2 LAST CDS_LIB pure_quanta
J 0
(-7650 4800);
DISPLAY INVISIBLE (-7650 4800);
FORCEADD UNIVERSAL_GND..1
(-7625 1425);
FORCEPROP 3 LASTPIN (-7625 1475) SIG_NAME GND\g
J 0
(-7615 1485);
DISPLAY 0.659574 (-7615 1485);
PAINT MONO (-7615 1485);
DISPLAY INVISIBLE (-7615 1485);
FORCEPROP 1 LAST PATH I3
J 0
(-7550 1425);
DISPLAY 0.872340 (-7550 1425);
PAINT AQUA (-7550 1425);
DISPLAY INVISIBLE (-7550 1425);
FORCEPROP 1 LAST HDL_POWER GND
J 1
(-7600 1350);
DISPLAY 0.872340 (-7600 1350);
PAINT GREEN (-7600 1350);
DISPLAY INVISIBLE (-7600 1350);
FORCEPROP 2 LAST CDS_LIB pure_quanta_power
J 0
(-7625 1425);
DISPLAY INVISIBLE (-7625 1425);
FORCEADD UNIVERSAL_GND..1
(-7325 4600);
FORCEPROP 3 LASTPIN (-7325 4650) SIG_NAME GND\g
J 0
(-7315 4660);
DISPLAY 0.659574 (-7315 4660);
PAINT MONO (-7315 4660);
DISPLAY INVISIBLE (-7315 4660);
FORCEPROP 1 LAST PATH I30
J 0
(-7250 4600);
DISPLAY 0.872340 (-7250 4600);
PAINT AQUA (-7250 4600);
DISPLAY INVISIBLE (-7250 4600);
FORCEPROP 1 LAST HDL_POWER GND
J 1
(-7300 4525);
DISPLAY 0.872340 (-7300 4525);
PAINT GREEN (-7300 4525);
DISPLAY INVISIBLE (-7300 4525);
FORCEPROP 2 LAST CDS_LIB pure_quanta_power
J 0
(-7325 4600);
DISPLAY INVISIBLE (-7325 4600);
FORCEADD OFFPAGE..1
(-6925 4475);
FORCEPROP 2 LAST $XR0 193 
J 0
(-7207 4475);
DISPLAY 0.638298 (-7207 4475);
PAINT MONO (-7207 4475);
FORCEPROP 2 LAST PATH I31
J 0
(-7200 4525);
DISPLAY 0.680851 (-7200 4525);
DISPLAY INVISIBLE (-7200 4525);
FORCEPROP 1 LAST COMMENT_BODY TRUE
J 0
(-6800 4375);
DISPLAY 0.872340 (-6800 4375);
PAINT GREEN (-6800 4375);
DISPLAY INVISIBLE (-6800 4375);
FORCEPROP 1 LAST OFFPAGE TRUE
J 0
(-6600 4350);
DISPLAY 0.872340 (-6600 4350);
PAINT GREEN (-6600 4350);
DISPLAY INVISIBLE (-6600 4350);
FORCEPROP 2 LAST CDS_LIB standard
J 2
(-6925 4475);
DISPLAY INVISIBLE (-6925 4475);
FORCEADD Q_RES..1
(-7000 4775);
FORCEPROP 1 LAST LOCATION PR358
J 0
(-7025 4825);
DISPLAY 0.489362 (-7025 4825);
PAINT SKYBLUE (-7025 4825);
FORCEPROP 0 LAST $SEC 1
J 0
(-7000 4850);
DISPLAY 0.680851 (-7000 4850);
PAINT MONO (-7000 4850);
DISPLAY INVISIBLE (-7000 4850);
FORCEPROP 0 LAST CDS_SEC 1
J 0
(-7000 4850);
DISPLAY 1.021277 (-7000 4850);
DISPLAY INVISIBLE (-7000 4850);
FORCEPROP 1 LASTPIN (-7100 4775) $PN 1
J 0
(-7088 4787);
DISPLAY 0.489362 (-7088 4787);
PAINT MONO (-7088 4787);
FORCEPROP 1 LASTPIN (-6900 4775) $PN 2
J 0
(-6938 4787);
DISPLAY 0.489362 (-6938 4787);
PAINT MONO (-6938 4787);
FORCEPROP 1 LAST TOLERANCE 1%
J 0
(-6875 4800);
DISPLAY 0.489362 (-6875 4800);
PAINT SKYBLUE (-6875 4800);
FORCEPROP 1 LAST PACK_TYPE 0402LF
J 0
(-6900 4725);
DISPLAY 0.489362 (-6900 4725);
PAINT SKYBLUE (-6900 4725);
FORCEPROP 1 LAST WATTAGE 1/16W
J 0
(-6900 4675);
DISPLAY 0.489362 (-6900 4675);
PAINT SKYBLUE (-6900 4675);
FORCEPROP 1 LAST MATERIAL EMPTY
J 0
(-7300 4675);
DISPLAY 0.489362 (-7300 4675);
PAINT RED (-7300 4675);
FORCEPROP 1 LAST VALUE 8.87K
J 2
(-7125 4800);
DISPLAY 0.489362 (-7125 4800);
PAINT SKYBLUE (-7125 4800);
FORCEPROP 1 LAST PART_NUMBER CS28872FB01
J 0
(-7300 4725);
DISPLAY 0.489362 (-7300 4725);
PAINT SKYBLUE (-7300 4725);
DISPLAY INVISIBLE (-7300 4725);
FORCEPROP 1 LAST PATH I32
J 0
(-7050 4925);
DISPLAY 0.978723 (-7050 4925);
PAINT WHITE (-7050 4925);
DISPLAY INVISIBLE (-7050 4925);
FORCEPROP 2 LAST CDS_LIB pure_quanta
J 0
(-7000 4775);
DISPLAY INVISIBLE (-7000 4775);
FORCEADD OFFPAGE..2
R 2
(-6950 4575);
FORCEPROP 2 LAST $XR0 198 
J 0
(-7235 4575);
DISPLAY 0.638298 (-7235 4575);
PAINT MONO (-7235 4575);
FORCEPROP 2 LAST $XR1 199 
J 0
(-7235 4539);
DISPLAY 0.638298 (-7235 4539);
PAINT MONO (-7235 4539);
FORCEPROP 2 LAST $XR2 193 
J 0
(-7355 4539);
DISPLAY 0.638298 (-7355 4539);
PAINT MONO (-7355 4539);
FORCEPROP 2 LAST PATH I33
J 0
(-7200 4625);
DISPLAY 0.680851 (-7200 4625);
DISPLAY INVISIBLE (-7200 4625);
FORCEPROP 1 LAST COMMENT_BODY TRUE
J 2
(-6905 4480);
DISPLAY 0.872340 (-6905 4480);
PAINT GREEN (-6905 4480);
DISPLAY INVISIBLE (-6905 4480);
FORCEPROP 1 LAST OFFPAGE TRUE
J 2
(-7275 4450);
DISPLAY 0.872340 (-7275 4450);
PAINT GREEN (-7275 4450);
DISPLAY INVISIBLE (-7275 4450);
FORCEPROP 2 LAST CDS_LIB standard
J 0
(-6950 4575);
DISPLAY INVISIBLE (-6950 4575);
FORCEADD UNIVERSAL_GND..1
(-7325 5225);
FORCEPROP 3 LASTPIN (-7325 5275) SIG_NAME GND\g
J 0
(-7315 5285);
DISPLAY 0.659574 (-7315 5285);
PAINT MONO (-7315 5285);
DISPLAY INVISIBLE (-7315 5285);
FORCEPROP 1 LAST PATH I34
J 0
(-7250 5225);
DISPLAY 0.872340 (-7250 5225);
PAINT AQUA (-7250 5225);
DISPLAY INVISIBLE (-7250 5225);
FORCEPROP 1 LAST HDL_POWER GND
J 1
(-7300 5150);
DISPLAY 0.872340 (-7300 5150);
PAINT GREEN (-7300 5150);
DISPLAY INVISIBLE (-7300 5150);
FORCEPROP 2 LAST CDS_LIB pure_quanta_power
J 0
(-7325 5225);
DISPLAY INVISIBLE (-7325 5225);
FORCEADD OFFPAGE..2
R 2
(-6975 5075);
FORCEPROP 2 LAST $XR0 193 
J 0
(-7230 5075);
DISPLAY 0.638298 (-7230 5075);
PAINT MONO (-7230 5075);
FORCEPROP 2 LAST PATH I35
J 0
(-7250 5125);
DISPLAY 0.680851 (-7250 5125);
DISPLAY INVISIBLE (-7250 5125);
FORCEPROP 1 LAST COMMENT_BODY TRUE
J 2
(-6930 4980);
DISPLAY 0.872340 (-6930 4980);
PAINT GREEN (-6930 4980);
DISPLAY INVISIBLE (-6930 4980);
FORCEPROP 1 LAST OFFPAGE TRUE
J 2
(-7300 4950);
DISPLAY 0.872340 (-7300 4950);
PAINT GREEN (-7300 4950);
DISPLAY INVISIBLE (-7300 4950);
FORCEPROP 2 LAST CDS_LIB standard
J 2
(-6975 5075);
DISPLAY INVISIBLE (-6975 5075);
FORCEADD Q_CAP..1
(-7325 5425);
FORCEPROP 1 LAST LOCATION PC579
J 0
(-7275 5525);
DISPLAY 0.489362 (-7275 5525);
PAINT SKYBLUE (-7275 5525);
FORCEPROP 0 LAST $SEC 1
J 0
(-7275 5575);
DISPLAY 0.680851 (-7275 5575);
PAINT MONO (-7275 5575);
DISPLAY INVISIBLE (-7275 5575);
FORCEPROP 0 LAST CDS_SEC 1
J 0
(-7275 5575);
DISPLAY 1.021277 (-7275 5575);
DISPLAY INVISIBLE (-7275 5575);
FORCEPROP 1 LASTPIN (-7325 5525) $PN 1
J 0
(-7315 5505);
DISPLAY 0.489362 (-7315 5505);
PAINT MONO (-7315 5505);
FORCEPROP 1 LASTPIN (-7325 5325) $PN 2
J 0
(-7315 5305);
DISPLAY 0.489362 (-7315 5305);
PAINT MONO (-7315 5305);
FORCEPROP 1 LAST TOLERANCE 10%
J 0
(-7275 5375);
DISPLAY 0.489362 (-7275 5375);
PAINT SKYBLUE (-7275 5375);
FORCEPROP 1 LAST MATERIAL X6S
J 0
(-7275 5325);
DISPLAY 0.489362 (-7275 5325);
PAINT SKYBLUE (-7275 5325);
FORCEPROP 1 LAST PACK_TYPE C0402
J 0
(-7275 5225);
DISPLAY 0.489362 (-7275 5225);
PAINT SKYBLUE (-7275 5225);
FORCEPROP 1 LAST VOLTAGE 10V
J 0
(-7275 5425);
DISPLAY 0.489362 (-7275 5425);
PAINT SKYBLUE (-7275 5425);
FORCEPROP 1 LAST VALUE 2.2UF
J 0
(-7275 5475);
DISPLAY 0.489362 (-7275 5475);
PAINT SKYBLUE (-7275 5475);
FORCEPROP 1 LAST PART_NUMBER CH5222KEB01
J 0
(-7275 5275);
DISPLAY 0.489362 (-7275 5275);
PAINT SKYBLUE (-7275 5275);
DISPLAY INVISIBLE (-7275 5275);
FORCEPROP 1 LAST PATH I36
J 0
(-7275 5575);
DISPLAY 0.978723 (-7275 5575);
PAINT WHITE (-7275 5575);
DISPLAY INVISIBLE (-7275 5575);
FORCEPROP 2 LAST CDS_LIB pure_quanta
J 0
(-7325 5425);
DISPLAY INVISIBLE (-7325 5425);
FORCEADD UNIVERSAL_GND..1
(-6975 5675);
FORCEPROP 3 LASTPIN (-6975 5725) SIG_NAME GND\g
J 0
(-6965 5735);
DISPLAY 0.659574 (-6965 5735);
PAINT MONO (-6965 5735);
DISPLAY INVISIBLE (-6965 5735);
FORCEPROP 1 LAST PATH I37
J 0
(-6900 5675);
DISPLAY 0.872340 (-6900 5675);
PAINT AQUA (-6900 5675);
DISPLAY INVISIBLE (-6900 5675);
FORCEPROP 1 LAST HDL_POWER GND
J 1
(-6950 5600);
DISPLAY 0.872340 (-6950 5600);
PAINT GREEN (-6950 5600);
DISPLAY INVISIBLE (-6950 5600);
FORCEPROP 2 LAST CDS_LIB pure_quanta_power
J 0
(-6975 5675);
DISPLAY INVISIBLE (-6975 5675);
FORCEADD Q_RES..2
(-7325 5925);
FORCEPROP 1 LAST LOCATION PR356
J 0
(-7280 6025);
DISPLAY 0.489362 (-7280 6025);
PAINT SKYBLUE (-7280 6025);
FORCEPROP 0 LAST $SEC 1
J 0
(-7275 6100);
DISPLAY 0.680851 (-7275 6100);
PAINT MONO (-7275 6100);
DISPLAY INVISIBLE (-7275 6100);
FORCEPROP 0 LAST CDS_SEC 1
J 0
(-7275 6100);
DISPLAY 1.021277 (-7275 6100);
DISPLAY INVISIBLE (-7275 6100);
FORCEPROP 1 LASTPIN (-7325 6025) $PN 1
J 0
(-7320 5987);
DISPLAY 0.489362 (-7320 5987);
PAINT MONO (-7320 5987);
FORCEPROP 1 LASTPIN (-7325 5825) $PN 2
J 0
(-7320 5835);
DISPLAY 0.489362 (-7320 5835);
PAINT MONO (-7320 5835);
FORCEPROP 1 LAST VALUE 2.2
J 0
(-7275 5975);
DISPLAY 0.489362 (-7275 5975);
PAINT SKYBLUE (-7275 5975);
FORCEPROP 1 LAST WATTAGE 1/16W
J 0
(-7275 5875);
DISPLAY 0.489362 (-7275 5875);
PAINT SKYBLUE (-7275 5875);
FORCEPROP 1 LAST MATERIAL CHIP
J 0
(-7275 5825);
DISPLAY 0.489362 (-7275 5825);
PAINT SKYBLUE (-7275 5825);
FORCEPROP 1 LAST TOLERANCE 1%
J 0
(-7275 5925);
DISPLAY 0.489362 (-7275 5925);
PAINT SKYBLUE (-7275 5925);
FORCEPROP 1 LAST PACK_TYPE 0402LF
J 0
(-7275 5725);
DISPLAY 0.489362 (-7275 5725);
PAINT SKYBLUE (-7275 5725);
FORCEPROP 1 LAST PART_NUMBER CS-2202FB01
J 0
(-7275 5775);
DISPLAY 0.489362 (-7275 5775);
PAINT SKYBLUE (-7275 5775);
DISPLAY INVISIBLE (-7275 5775);
FORCEPROP 1 LAST PATH I38
J 0
(-7275 6100);
DISPLAY 0.978723 (-7275 6100);
PAINT WHITE (-7275 6100);
DISPLAY INVISIBLE (-7275 6100);
FORCEPROP 2 LAST CDS_LIB pure_quanta
J 0
(-7325 5925);
DISPLAY INVISIBLE (-7325 5925);
FORCEADD VCC_CORE..1
(-7325 6325);
FORCEPROP 3 LASTPIN (-7325 6275) SIG_NAME PVDDCR_CPU0_P0_PVCC\g
J 0
(-7315 6285);
DISPLAY 0.659574 (-7315 6285);
PAINT MONO (-7315 6285);
DISPLAY INVISIBLE (-7315 6285);
FORCEPROP 1 LAST HDL_POWER PVDDCR_CPU0_P0_PVCC
J 1
(-7325 6375);
DISPLAY 0.489362 (-7325 6375);
PAINT GREEN (-7325 6375);
FORCEPROP 1 LAST PATH I39
J 0
(-7275 6350);
DISPLAY 0.872340 (-7275 6350);
PAINT AQUA (-7275 6350);
DISPLAY INVISIBLE (-7275 6350);
FORCEPROP 2 LAST CDS_LIB pure_quanta_power
J 0
(-7325 6325);
DISPLAY INVISIBLE (-7325 6325);
FORCEADD Q_CAP..1
(-7625 1700);
FORCEPROP 1 LAST LOCATION PC578_8
J 0
(-7575 1800);
DISPLAY 0.489362 (-7575 1800);
PAINT SKYBLUE (-7575 1800);
FORCEPROP 0 LAST $SEC 1
J 0
(-7575 1825);
DISPLAY 0.680851 (-7575 1825);
PAINT MONO (-7575 1825);
DISPLAY INVISIBLE (-7575 1825);
FORCEPROP 0 LAST CDS_SEC 1
J 0
(-7575 1825);
DISPLAY 1.021277 (-7575 1825);
DISPLAY INVISIBLE (-7575 1825);
FORCEPROP 1 LASTPIN (-7625 1800) $PN 1
J 0
(-7615 1780);
DISPLAY 0.489362 (-7615 1780);
PAINT MONO (-7615 1780);
FORCEPROP 1 LASTPIN (-7625 1600) $PN 2
J 0
(-7615 1580);
DISPLAY 0.489362 (-7615 1580);
PAINT MONO (-7615 1580);
FORCEPROP 1 LAST TOLERANCE 10%
J 0
(-7575 1650);
DISPLAY 0.489362 (-7575 1650);
PAINT SKYBLUE (-7575 1650);
FORCEPROP 1 LAST VOLTAGE 25V
J 0
(-7575 1700);
DISPLAY 0.489362 (-7575 1700);
PAINT SKYBLUE (-7575 1700);
FORCEPROP 1 LAST VALUE 0.1UF
J 0
(-7575 1750);
DISPLAY 0.489362 (-7575 1750);
PAINT SKYBLUE (-7575 1750);
FORCEPROP 1 LAST MATERIAL X7R
J 0
(-7575 1600);
DISPLAY 0.489362 (-7575 1600);
PAINT SKYBLUE (-7575 1600);
FORCEPROP 1 LAST PACK_TYPE 0402
J 0
(-7575 1500);
DISPLAY 0.489362 (-7575 1500);
PAINT SKYBLUE (-7575 1500);
FORCEPROP 1 LAST PART_NUMBER CH4104K1B00
J 0
(-7575 1550);
DISPLAY 0.489362 (-7575 1550);
PAINT SKYBLUE (-7575 1550);
DISPLAY INVISIBLE (-7575 1550);
FORCEPROP 1 LAST PATH I4
J 0
(-7575 1850);
DISPLAY 0.978723 (-7575 1850);
PAINT WHITE (-7575 1850);
DISPLAY INVISIBLE (-7575 1850);
FORCEPROP 2 LAST CDS_LIB pure_quanta
J 0
(-7625 1700);
DISPLAY INVISIBLE (-7625 1700);
FORCEADD Q_CAP..1
(-6975 5925);
FORCEPROP 1 LAST LOCATION PC581_SOP0_1
J 0
(-6925 6025);
DISPLAY 0.489362 (-6925 6025);
PAINT SKYBLUE (-6925 6025);
FORCEPROP 0 LAST $SEC 1
J 0
(-6925 6075);
DISPLAY 0.680851 (-6925 6075);
PAINT MONO (-6925 6075);
DISPLAY INVISIBLE (-6925 6075);
FORCEPROP 0 LAST CDS_SEC 1
J 0
(-6925 6075);
DISPLAY 1.021277 (-6925 6075);
DISPLAY INVISIBLE (-6925 6075);
FORCEPROP 1 LASTPIN (-6975 6025) $PN 1
J 0
(-6965 6005);
DISPLAY 0.489362 (-6965 6005);
PAINT MONO (-6965 6005);
FORCEPROP 1 LASTPIN (-6975 5825) $PN 2
J 0
(-6965 5805);
DISPLAY 0.489362 (-6965 5805);
PAINT MONO (-6965 5805);
FORCEPROP 1 LAST TOLERANCE 10%
J 0
(-6925 5875);
DISPLAY 0.489362 (-6925 5875);
PAINT SKYBLUE (-6925 5875);
FORCEPROP 1 LAST MATERIAL X6S
J 0
(-6925 5825);
DISPLAY 0.489362 (-6925 5825);
PAINT SKYBLUE (-6925 5825);
FORCEPROP 1 LAST PACK_TYPE C0402
J 0
(-6925 5725);
DISPLAY 0.489362 (-6925 5725);
PAINT SKYBLUE (-6925 5725);
FORCEPROP 1 LAST VOLTAGE 10V
J 0
(-6925 5925);
DISPLAY 0.489362 (-6925 5925);
PAINT SKYBLUE (-6925 5925);
FORCEPROP 1 LAST VALUE 2.2UF
J 0
(-6925 5975);
DISPLAY 0.489362 (-6925 5975);
PAINT SKYBLUE (-6925 5975);
FORCEPROP 1 LAST PART_NUMBER CH5222KEB01
J 0
(-6925 5775);
DISPLAY 0.489362 (-6925 5775);
PAINT SKYBLUE (-6925 5775);
DISPLAY INVISIBLE (-6925 5775);
FORCEPROP 1 LAST PATH I40
J 0
(-6925 6075);
DISPLAY 0.978723 (-6925 6075);
PAINT WHITE (-6925 6075);
DISPLAY INVISIBLE (-6925 6075);
FORCEPROP 2 LAST CDS_LIB pure_quanta
J 0
(-6975 5925);
DISPLAY INVISIBLE (-6975 5925);
FORCEADD ISL99390FRZTR5935..1
(-5825 5075);
FORCEPROP 1 LAST LOCATION PU49
J 0
(-6125 5950);
DISPLAY 0.489362 (-6125 5950);
PAINT SKYBLUE (-6125 5950);
FORCEPROP 0 LAST $SEC 1
J 0
(-6125 6100);
DISPLAY 0.680851 (-6125 6100);
PAINT MONO (-6125 6100);
DISPLAY INVISIBLE (-6125 6100);
FORCEPROP 0 LAST CDS_SEC 1
J 0
(-6125 6100);
DISPLAY 1.021277 (-6125 6100);
DISPLAY INVISIBLE (-6125 6100);
FORCEPROP 0 LASTPIN (-5425 4625) $PN 2
J 0
(-5415 4635);
DISPLAY 0.489362 (-5415 4635);
PAINT MONO (-5415 4635);
FORCEPROP 0 LASTPIN (-5425 5425) $PN 33
J 0
(-5415 5435);
DISPLAY 0.489362 (-5415 5435);
PAINT MONO (-5415 5435);
FORCEPROP 0 LASTPIN (-6275 4825) $PN 31
J 2
(-6285 4835);
DISPLAY 0.489362 (-6285 4835);
PAINT MONO (-6285 4835);
FORCEPROP 0 LASTPIN (-6275 5225) $PN 35
J 2
(-6285 5235);
DISPLAY 0.489362 (-6285 5235);
PAINT MONO (-6285 5235);
FORCEPROP 0 LASTPIN (-5425 4775) $PN 6
J 0
(-5415 4785);
DISPLAY 0.489362 (-5415 4785);
PAINT MONO (-5415 4785);
FORCEPROP 0 LASTPIN (-5425 4725) $PN 41
J 0
(-5415 4735);
DISPLAY 0.489362 (-5415 4735);
PAINT MONO (-5415 4735);
FORCEPROP 0 LASTPIN (-6275 5075) $PN 38
J 2
(-6285 5085);
DISPLAY 0.489362 (-6285 5085);
PAINT MONO (-6285 5085);
FORCEPROP 0 LASTPIN (-6275 4775) $PN 37
J 2
(-6285 4785);
DISPLAY 0.489362 (-6285 4785);
PAINT MONO (-6285 4785);
FORCEPROP 0 LASTPIN (-5425 4575) $PN 5
J 0
(-5415 4585);
DISPLAY 0.489362 (-5415 4585);
PAINT MONO (-5415 4585);
FORCEPROP 0 LASTPIN (-5425 4525) $PN 7_9-20_24
J 0
(-5415 4535);
DISPLAY 0.489362 (-5415 4535);
PAINT MONO (-5415 4535);
FORCEPROP 0 LASTPIN (-5425 4475) $PN 40
J 0
(-5415 4485);
DISPLAY 0.489362 (-5415 4485);
PAINT MONO (-5415 4485);
FORCEPROP 0 LASTPIN (-5425 5175) $PN 32
J 0
(-5415 5185);
DISPLAY 0.489362 (-5415 5185);
PAINT MONO (-5415 5185);
FORCEPROP 0 LASTPIN (-6275 5725) $PN 4
J 2
(-6285 5735);
DISPLAY 0.489362 (-6285 5735);
PAINT MONO (-6285 5735);
FORCEPROP 0 LASTPIN (-6275 4475) $PN 34
J 2
(-6285 4485);
DISPLAY 0.489362 (-6285 4485);
PAINT MONO (-6285 4485);
FORCEPROP 0 LASTPIN (-6275 4975) $PN 39
J 2
(-6285 4985);
DISPLAY 0.489362 (-6285 4985);
PAINT MONO (-6285 4985);
FORCEPROP 0 LASTPIN (-5425 5075) $PN 10_19
J 0
(-5415 5085);
DISPLAY 0.489362 (-5415 5085);
PAINT MONO (-5415 5085);
FORCEPROP 0 LASTPIN (-6275 4575) $PN 36
J 2
(-6285 4585);
DISPLAY 0.489362 (-6285 4585);
PAINT MONO (-6285 4585);
FORCEPROP 0 LASTPIN (-6275 5425) $PN 3
J 2
(-6285 5435);
DISPLAY 0.489362 (-6285 5435);
PAINT MONO (-6285 5435);
FORCEPROP 0 LASTPIN (-5425 5725) $PN 25_29
J 0
(-5415 5735);
DISPLAY 0.489362 (-5415 5735);
PAINT MONO (-5415 5735);
FORCEPROP 0 LASTPIN (-5425 5675) $PN 30
J 0
(-5415 5685);
DISPLAY 0.489362 (-5415 5685);
PAINT MONO (-5415 5685);
FORCEPROP 0 LASTPIN (-5425 4825) $PN 1
J 0
(-5415 4835);
DISPLAY 0.489362 (-5415 4835);
PAINT MONO (-5415 4835);
FORCEPROP 2 LAST VALUE ISL99390FRZ-TR5935
J 0
(-6125 6000);
DISPLAY 0.489362 (-6125 6000);
PAINT SKYBLUE (-6125 6000);
FORCEPROP 2 LAST PART_TYPE SMLF
J 0
(-6125 6050);
DISPLAY 1.021277 (-6125 6050);
FORCEPROP 1 LAST MATERIAL IC
J 0
(-6125 5800);
DISPLAY 0.489362 (-6125 5800);
PAINT SKYBLUE (-6125 5800);
FORCEPROP 1 LAST PART_NUMBER AL099390004
J 0
(-6125 5875);
DISPLAY 0.489362 (-6125 5875);
PAINT SKYBLUE (-6125 5875);
DISPLAY INVISIBLE (-6125 5875);
FORCEPROP 1 LAST PATH I41
J 0
(-5825 5075);
DISPLAY 0.723404 (-5825 5075);
PAINT GREEN (-5825 5075);
DISPLAY INVISIBLE (-5825 5075);
FORCEPROP 2 LAST CDS_LIB pure_quanta
J 0
(-5825 5075);
DISPLAY INVISIBLE (-5825 5075);
FORCEPROP 1 LAST NEEDS_NO_SIZE TRUE
J 0
(-5825 5075);
DISPLAY 0.723404 (-5825 5075);
PAINT GREEN (-5825 5075);
DISPLAY INVISIBLE (-5825 5075);
FORCEPROP 1 LAST CDS_LMAN_SYM_OUTLINE -300,700,250,-650
J 0
(-5825 5075);
DISPLAY 0.468085 (-5825 5075);
PAINT GREEN (-5825 5075);
DISPLAY INVISIBLE (-5825 5075);
FORCEADD UNIVERSAL_GND..1
(-5250 4350);
FORCEPROP 3 LASTPIN (-5250 4400) SIG_NAME GND\g
J 0
(-5240 4410);
DISPLAY 0.659574 (-5240 4410);
PAINT MONO (-5240 4410);
DISPLAY INVISIBLE (-5240 4410);
FORCEPROP 1 LAST PATH I42
J 0
(-5175 4350);
DISPLAY 0.872340 (-5175 4350);
PAINT AQUA (-5175 4350);
DISPLAY INVISIBLE (-5175 4350);
FORCEPROP 1 LAST HDL_POWER GND
J 1
(-5225 4275);
DISPLAY 0.872340 (-5225 4275);
PAINT GREEN (-5225 4275);
DISPLAY INVISIBLE (-5225 4275);
FORCEPROP 2 LAST CDS_LIB pure_quanta_power
J 0
(-5250 4350);
DISPLAY INVISIBLE (-5250 4350);
FORCEADD Q_CAP..1
(-5225 5925);
FORCEPROP 1 LAST LOCATION PC583_1
J 0
(-5175 6025);
DISPLAY 0.489362 (-5175 6025);
PAINT SKYBLUE (-5175 6025);
FORCEPROP 0 LAST $SEC 1
J 0
(-5175 6075);
DISPLAY 0.680851 (-5175 6075);
PAINT MONO (-5175 6075);
DISPLAY INVISIBLE (-5175 6075);
FORCEPROP 0 LAST CDS_SEC 1
J 0
(-5175 6075);
DISPLAY 1.021277 (-5175 6075);
DISPLAY INVISIBLE (-5175 6075);
FORCEPROP 1 LASTPIN (-5225 6025) $PN 1
J 0
(-5215 6005);
DISPLAY 0.489362 (-5215 6005);
PAINT MONO (-5215 6005);
FORCEPROP 1 LASTPIN (-5225 5825) $PN 2
J 0
(-5215 5805);
DISPLAY 0.489362 (-5215 5805);
PAINT MONO (-5215 5805);
FORCEPROP 1 LAST PACK_TYPE 0402
J 0
(-5175 5725);
DISPLAY 0.489362 (-5175 5725);
PAINT SKYBLUE (-5175 5725);
FORCEPROP 1 LAST TOLERANCE 10%
J 0
(-5175 5875);
DISPLAY 0.489362 (-5175 5875);
PAINT SKYBLUE (-5175 5875);
FORCEPROP 1 LAST MATERIAL X7R
J 0
(-5175 5825);
DISPLAY 0.489362 (-5175 5825);
PAINT SKYBLUE (-5175 5825);
FORCEPROP 1 LAST VALUE 0.1UF
J 0
(-5175 5975);
DISPLAY 0.489362 (-5175 5975);
PAINT SKYBLUE (-5175 5975);
FORCEPROP 1 LAST VOLTAGE 25V
J 0
(-5175 5925);
DISPLAY 0.489362 (-5175 5925);
PAINT SKYBLUE (-5175 5925);
FORCEPROP 1 LAST PART_NUMBER CH4104K1B00
J 0
(-5175 5775);
DISPLAY 0.489362 (-5175 5775);
PAINT SKYBLUE (-5175 5775);
DISPLAY INVISIBLE (-5175 5775);
FORCEPROP 1 LAST PATH I43
J 0
(-5175 6075);
DISPLAY 0.978723 (-5175 6075);
PAINT WHITE (-5175 6075);
DISPLAY INVISIBLE (-5175 6075);
FORCEPROP 2 LAST CDS_LIB pure_quanta
J 0
(-5225 5925);
DISPLAY INVISIBLE (-5225 5925);
FORCEADD Q_CAP..1
(-4900 5925);
FORCEPROP 1 LAST LOCATION PC585_1
J 0
(-4850 6025);
DISPLAY 0.489362 (-4850 6025);
PAINT SKYBLUE (-4850 6025);
FORCEPROP 0 LAST $SEC 1
J 0
(-4850 6050);
DISPLAY 0.680851 (-4850 6050);
PAINT MONO (-4850 6050);
DISPLAY INVISIBLE (-4850 6050);
FORCEPROP 0 LAST CDS_SEC 1
J 0
(-4850 6050);
DISPLAY 1.021277 (-4850 6050);
DISPLAY INVISIBLE (-4850 6050);
FORCEPROP 1 LASTPIN (-4900 6025) $PN 1
J 0
(-4890 6005);
DISPLAY 0.489362 (-4890 6005);
PAINT MONO (-4890 6005);
FORCEPROP 1 LASTPIN (-4900 5825) $PN 2
J 0
(-4890 5805);
DISPLAY 0.489362 (-4890 5805);
PAINT MONO (-4890 5805);
FORCEPROP 1 LAST VALUE 1UF
J 0
(-4850 5975);
DISPLAY 0.489362 (-4850 5975);
PAINT SKYBLUE (-4850 5975);
FORCEPROP 1 LAST PACK_TYPE C0402
J 0
(-4850 5725);
DISPLAY 0.489362 (-4850 5725);
PAINT SKYBLUE (-4850 5725);
FORCEPROP 1 LAST MATERIAL X6S
J 0
(-4850 5825);
DISPLAY 0.489362 (-4850 5825);
PAINT SKYBLUE (-4850 5825);
FORCEPROP 1 LAST TOLERANCE 10%
J 0
(-4850 5875);
DISPLAY 0.489362 (-4850 5875);
PAINT SKYBLUE (-4850 5875);
FORCEPROP 1 LAST VOLTAGE 25V
J 0
(-4850 5925);
DISPLAY 0.489362 (-4850 5925);
PAINT SKYBLUE (-4850 5925);
FORCEPROP 1 LAST PART_NUMBER CH5104KEB02
J 0
(-4850 5775);
DISPLAY 0.489362 (-4850 5775);
PAINT SKYBLUE (-4850 5775);
DISPLAY INVISIBLE (-4850 5775);
FORCEPROP 1 LAST PATH I44
J 0
(-4850 6075);
DISPLAY 0.978723 (-4850 6075);
PAINT WHITE (-4850 6075);
DISPLAY INVISIBLE (-4850 6075);
FORCEPROP 2 LAST CDS_LIB pure_quanta
J 0
(-4900 5925);
DISPLAY INVISIBLE (-4900 5925);
FORCEADD Q_RES..2
(-4475 4375);
FORCEPROP 1 LAST LOCATION PR502
J 0
(-4430 4475);
DISPLAY 0.489362 (-4430 4475);
PAINT SKYBLUE (-4430 4475);
FORCEPROP 0 LAST $SEC 1
J 0
(-4425 4550);
DISPLAY 0.680851 (-4425 4550);
PAINT MONO (-4425 4550);
DISPLAY INVISIBLE (-4425 4550);
FORCEPROP 0 LAST CDS_SEC 1
J 0
(-4425 4550);
DISPLAY 1.021277 (-4425 4550);
DISPLAY INVISIBLE (-4425 4550);
FORCEPROP 1 LASTPIN (-4475 4475) $PN 1
J 0
(-4470 4437);
DISPLAY 0.489362 (-4470 4437);
PAINT MONO (-4470 4437);
FORCEPROP 1 LASTPIN (-4475 4275) $PN 2
J 0
(-4470 4285);
DISPLAY 0.489362 (-4470 4285);
PAINT MONO (-4470 4285);
FORCEPROP 1 LAST PACK_TYPE 0402LF
J 0
(-4435 4175);
DISPLAY 0.489362 (-4435 4175);
PAINT SKYBLUE (-4435 4175);
FORCEPROP 1 LAST MATERIAL EMPTY
J 0
(-4435 4275);
DISPLAY 0.489362 (-4435 4275);
PAINT RED (-4435 4275);
FORCEPROP 1 LAST WATTAGE 1/8W
J 0
(-4435 4325);
DISPLAY 0.489362 (-4435 4325);
PAINT SKYBLUE (-4435 4325);
FORCEPROP 1 LAST VALUE 1.5
J 0
(-4430 4425);
DISPLAY 0.489362 (-4430 4425);
PAINT SKYBLUE (-4430 4425);
FORCEPROP 1 LAST TOLERANCE 1%
J 0
(-4430 4400);
DISPLAY 0.489362 (-4430 4400);
PAINT SKYBLUE (-4430 4400);
FORCEPROP 1 LAST PART_NUMBER CS-1504FB00
J 0
(-4435 4225);
DISPLAY 0.489362 (-4435 4225);
PAINT SKYBLUE (-4435 4225);
DISPLAY INVISIBLE (-4435 4225);
FORCEPROP 1 LAST PATH I45
J 0
(-4425 4550);
DISPLAY 0.978723 (-4425 4550);
PAINT WHITE (-4425 4550);
DISPLAY INVISIBLE (-4425 4550);
FORCEPROP 2 LAST CDS_LIB pure_quanta
J 0
(-4475 4375);
DISPLAY INVISIBLE (-4475 4375);
FORCEADD Q_CAP..1
(-4475 4825);
FORCEPROP 1 LAST LOCATION PC185
J 0
(-4425 4925);
DISPLAY 0.489362 (-4425 4925);
PAINT SKYBLUE (-4425 4925);
FORCEPROP 0 LAST $SEC 1
J 0
(-4425 4975);
DISPLAY 0.680851 (-4425 4975);
PAINT MONO (-4425 4975);
DISPLAY INVISIBLE (-4425 4975);
FORCEPROP 0 LAST CDS_SEC 1
J 0
(-4425 4975);
DISPLAY 1.021277 (-4425 4975);
DISPLAY INVISIBLE (-4425 4975);
FORCEPROP 1 LASTPIN (-4475 4925) $PN 1
J 0
(-4465 4905);
DISPLAY 0.489362 (-4465 4905);
PAINT MONO (-4465 4905);
FORCEPROP 1 LASTPIN (-4475 4725) $PN 2
J 0
(-4465 4705);
DISPLAY 0.489362 (-4465 4705);
PAINT MONO (-4465 4705);
FORCEPROP 1 LAST MATERIAL EMPTY
J 0
(-4425 4725);
DISPLAY 0.489362 (-4425 4725);
PAINT RED (-4425 4725);
FORCEPROP 1 LAST PACK_TYPE C0402
J 0
(-4425 4625);
DISPLAY 0.489362 (-4425 4625);
PAINT SKYBLUE (-4425 4625);
FORCEPROP 1 LAST VALUE 560PF
J 0
(-4425 4875);
DISPLAY 0.489362 (-4425 4875);
PAINT SKYBLUE (-4425 4875);
FORCEPROP 1 LAST TOLERANCE 10%
J 0
(-4425 4775);
DISPLAY 0.489362 (-4425 4775);
PAINT SKYBLUE (-4425 4775);
FORCEPROP 1 LAST VOLTAGE 50V
J 0
(-4425 4825);
DISPLAY 0.489362 (-4425 4825);
PAINT SKYBLUE (-4425 4825);
FORCEPROP 1 LAST PART_NUMBER CH1566K1B09
J 0
(-4425 4675);
DISPLAY 0.489362 (-4425 4675);
PAINT SKYBLUE (-4425 4675);
DISPLAY INVISIBLE (-4425 4675);
FORCEPROP 1 LAST PATH I46
J 0
(-4425 4975);
DISPLAY 0.978723 (-4425 4975);
PAINT WHITE (-4425 4975);
DISPLAY INVISIBLE (-4425 4975);
FORCEPROP 2 LAST CDS_LIB pure_quanta
J 0
(-4475 4825);
DISPLAY INVISIBLE (-4475 4825);
FORCEADD OFFPAGE..3
R 2
(-3800 4825);
FORCEPROP 2 LAST $XR0 198 
J 0
(-4080 4825);
DISPLAY 0.638298 (-4080 4825);
PAINT MONO (-4080 4825);
FORCEPROP 2 LAST PATH I47
J 0
(-4100 4875);
DISPLAY 0.680851 (-4100 4875);
DISPLAY INVISIBLE (-4100 4875);
FORCEPROP 1 LAST COMMENT_BODY TRUE
J 2
(-3750 4725);
DISPLAY 0.872340 (-3750 4725);
PAINT GREEN (-3750 4725);
DISPLAY INVISIBLE (-3750 4725);
FORCEPROP 1 LAST OFFPAGE TRUE
J 2
(-4125 4700);
DISPLAY 0.872340 (-4125 4700);
PAINT GREEN (-4125 4700);
DISPLAY INVISIBLE (-4125 4700);
FORCEPROP 2 LAST CDS_LIB standard
J 2
(-3800 4825);
DISPLAY INVISIBLE (-3800 4825);
FORCEADD Q_RES..1
(-4525 5425);
FORCEPROP 1 LAST LOCATION PR360
J 0
(-4550 5475);
DISPLAY 0.489362 (-4550 5475);
PAINT SKYBLUE (-4550 5475);
FORCEPROP 0 LAST $SEC 1
J 0
(-4500 5500);
DISPLAY 0.680851 (-4500 5500);
PAINT MONO (-4500 5500);
DISPLAY INVISIBLE (-4500 5500);
FORCEPROP 0 LAST CDS_SEC 1
J 0
(-4500 5500);
DISPLAY 1.021277 (-4500 5500);
DISPLAY INVISIBLE (-4500 5500);
FORCEPROP 1 LASTPIN (-4625 5425) $PN 1
J 0
(-4613 5437);
DISPLAY 0.489362 (-4613 5437);
PAINT MONO (-4613 5437);
FORCEPROP 1 LASTPIN (-4425 5425) $PN 2
J 0
(-4463 5437);
DISPLAY 0.489362 (-4463 5437);
PAINT MONO (-4463 5437);
FORCEPROP 1 LAST MATERIAL CHIP
J 0
(-4775 5325);
DISPLAY 0.489362 (-4775 5325);
PAINT SKYBLUE (-4775 5325);
FORCEPROP 1 LAST TOLERANCE 1%
J 0
(-4425 5450);
DISPLAY 0.489362 (-4425 5450);
PAINT SKYBLUE (-4425 5450);
FORCEPROP 1 LAST VALUE 5.6
J 2
(-4625 5450);
DISPLAY 0.489362 (-4625 5450);
PAINT SKYBLUE (-4625 5450);
FORCEPROP 1 LAST PACK_TYPE 0402LF
J 0
(-4425 5325);
DISPLAY 0.489362 (-4425 5325);
PAINT SKYBLUE (-4425 5325);
FORCEPROP 1 LAST WATTAGE 1/16W
J 0
(-4425 5375);
DISPLAY 0.489362 (-4425 5375);
PAINT SKYBLUE (-4425 5375);
FORCEPROP 1 LAST PART_NUMBER CS-5602FB01
J 0
(-4775 5375);
DISPLAY 0.489362 (-4775 5375);
PAINT SKYBLUE (-4775 5375);
DISPLAY INVISIBLE (-4775 5375);
FORCEPROP 1 LAST PATH I48
J 0
(-4575 5575);
DISPLAY 0.978723 (-4575 5575);
PAINT WHITE (-4575 5575);
DISPLAY INVISIBLE (-4575 5575);
FORCEPROP 2 LAST CDS_LIB pure_quanta
J 0
(-4525 5425);
DISPLAY INVISIBLE (-4525 5425);
FORCEADD Q_CAP..1
(-4575 5925);
FORCEPROP 1 LAST LOCATION PC587_1
J 0
(-4525 6025);
DISPLAY 0.489362 (-4525 6025);
PAINT SKYBLUE (-4525 6025);
FORCEPROP 0 LAST $SEC 1
J 0
(-4525 6050);
DISPLAY 0.680851 (-4525 6050);
PAINT MONO (-4525 6050);
DISPLAY INVISIBLE (-4525 6050);
FORCEPROP 0 LAST CDS_SEC 1
J 0
(-4525 6050);
DISPLAY 1.021277 (-4525 6050);
DISPLAY INVISIBLE (-4525 6050);
FORCEPROP 1 LASTPIN (-4575 6025) $PN 1
J 0
(-4565 6005);
DISPLAY 0.489362 (-4565 6005);
PAINT MONO (-4565 6005);
FORCEPROP 1 LASTPIN (-4575 5825) $PN 2
J 0
(-4565 5805);
DISPLAY 0.489362 (-4565 5805);
PAINT MONO (-4565 5805);
FORCEPROP 1 LAST VOLTAGE 16V
J 0
(-4525 5925);
DISPLAY 0.489362 (-4525 5925);
PAINT SKYBLUE (-4525 5925);
FORCEPROP 1 LAST VALUE 22UF
J 0
(-4525 5975);
DISPLAY 0.489362 (-4525 5975);
PAINT SKYBLUE (-4525 5975);
FORCEPROP 1 LAST TOLERANCE 20%
J 0
(-4525 5875);
DISPLAY 0.489362 (-4525 5875);
PAINT SKYBLUE (-4525 5875);
FORCEPROP 1 LAST MATERIAL X6S
J 0
(-4525 5825);
DISPLAY 0.489362 (-4525 5825);
PAINT SKYBLUE (-4525 5825);
FORCEPROP 1 LAST PACK_TYPE C0805
J 0
(-4525 5725);
DISPLAY 0.489362 (-4525 5725);
PAINT SKYBLUE (-4525 5725);
FORCEPROP 1 LAST PART_NUMBER CH6223MEA01
J 0
(-4525 5775);
DISPLAY 0.489362 (-4525 5775);
PAINT SKYBLUE (-4525 5775);
DISPLAY INVISIBLE (-4525 5775);
FORCEPROP 1 LAST PATH I49
J 0
(-4525 6075);
DISPLAY 0.978723 (-4525 6075);
PAINT WHITE (-4525 6075);
DISPLAY INVISIBLE (-4525 6075);
FORCEPROP 2 LAST CDS_LIB pure_quanta
J 0
(-4575 5925);
DISPLAY INVISIBLE (-4575 5925);
FORCEADD UNIVERSAL_GND..1
(-7300 1500);
FORCEPROP 3 LASTPIN (-7300 1550) SIG_NAME GND\g
J 0
(-7290 1560);
DISPLAY 0.659574 (-7290 1560);
PAINT MONO (-7290 1560);
DISPLAY INVISIBLE (-7290 1560);
FORCEPROP 1 LAST PATH I5
J 0
(-7225 1500);
DISPLAY 0.872340 (-7225 1500);
PAINT AQUA (-7225 1500);
DISPLAY INVISIBLE (-7225 1500);
FORCEPROP 1 LAST HDL_POWER GND
J 1
(-7275 1425);
DISPLAY 0.872340 (-7275 1425);
PAINT GREEN (-7275 1425);
DISPLAY INVISIBLE (-7275 1425);
FORCEPROP 2 LAST CDS_LIB pure_quanta_power
J 0
(-7300 1500);
DISPLAY INVISIBLE (-7300 1500);
FORCEADD Q_CAP..1
(-4250 5925);
FORCEPROP 1 LAST LOCATION PC589_1
J 0
(-4200 6025);
DISPLAY 0.489362 (-4200 6025);
PAINT SKYBLUE (-4200 6025);
FORCEPROP 0 LAST $SEC 1
J 0
(-4200 6050);
DISPLAY 0.680851 (-4200 6050);
PAINT MONO (-4200 6050);
DISPLAY INVISIBLE (-4200 6050);
FORCEPROP 0 LAST CDS_SEC 1
J 0
(-4200 6050);
DISPLAY 1.021277 (-4200 6050);
DISPLAY INVISIBLE (-4200 6050);
FORCEPROP 1 LASTPIN (-4250 6025) $PN 1
J 0
(-4240 6005);
DISPLAY 0.489362 (-4240 6005);
PAINT MONO (-4240 6005);
FORCEPROP 1 LASTPIN (-4250 5825) $PN 2
J 0
(-4240 5805);
DISPLAY 0.489362 (-4240 5805);
PAINT MONO (-4240 5805);
FORCEPROP 1 LAST VOLTAGE 16V
J 0
(-4200 5925);
DISPLAY 0.489362 (-4200 5925);
PAINT SKYBLUE (-4200 5925);
FORCEPROP 1 LAST TOLERANCE 20%
J 0
(-4200 5875);
DISPLAY 0.489362 (-4200 5875);
PAINT SKYBLUE (-4200 5875);
FORCEPROP 1 LAST VALUE 22UF
J 0
(-4200 5975);
DISPLAY 0.489362 (-4200 5975);
PAINT SKYBLUE (-4200 5975);
FORCEPROP 1 LAST PACK_TYPE C0805
J 0
(-4200 5725);
DISPLAY 0.489362 (-4200 5725);
PAINT SKYBLUE (-4200 5725);
FORCEPROP 1 LAST MATERIAL X6S
J 0
(-4200 5825);
DISPLAY 0.489362 (-4200 5825);
PAINT SKYBLUE (-4200 5825);
FORCEPROP 1 LAST PART_NUMBER CH6223MEA01
J 0
(-4200 5775);
DISPLAY 0.489362 (-4200 5775);
PAINT SKYBLUE (-4200 5775);
DISPLAY INVISIBLE (-4200 5775);
FORCEPROP 1 LAST PATH I50
J 0
(-4200 6075);
DISPLAY 0.978723 (-4200 6075);
PAINT WHITE (-4200 6075);
DISPLAY INVISIBLE (-4200 6075);
FORCEPROP 2 LAST CDS_LIB pure_quanta
J 0
(-4250 5925);
DISPLAY INVISIBLE (-4250 5925);
FORCEADD Q_CAP..1
(-4025 5925);
FORCEPROP 1 LAST LOCATION PC591_1
J 0
(-3975 6025);
DISPLAY 0.489362 (-3975 6025);
PAINT SKYBLUE (-3975 6025);
FORCEPROP 0 LAST $SEC 1
J 0
(-3975 6050);
DISPLAY 0.680851 (-3975 6050);
PAINT MONO (-3975 6050);
DISPLAY INVISIBLE (-3975 6050);
FORCEPROP 0 LAST CDS_SEC 1
J 0
(-3975 6050);
DISPLAY 1.021277 (-3975 6050);
DISPLAY INVISIBLE (-3975 6050);
FORCEPROP 1 LASTPIN (-4025 6025) $PN 1
J 0
(-4015 6005);
DISPLAY 0.489362 (-4015 6005);
PAINT MONO (-4015 6005);
FORCEPROP 1 LASTPIN (-4025 5825) $PN 2
J 0
(-4015 5805);
DISPLAY 0.489362 (-4015 5805);
PAINT MONO (-4015 5805);
FORCEPROP 1 LAST PACK_TYPE C0805
J 0
(-3975 5725);
DISPLAY 0.489362 (-3975 5725);
PAINT SKYBLUE (-3975 5725);
FORCEPROP 1 LAST MATERIAL X6S
J 0
(-3975 5825);
DISPLAY 0.489362 (-3975 5825);
PAINT SKYBLUE (-3975 5825);
FORCEPROP 1 LAST VOLTAGE 16V
J 0
(-3975 5925);
DISPLAY 0.489362 (-3975 5925);
PAINT SKYBLUE (-3975 5925);
FORCEPROP 1 LAST TOLERANCE 20%
J 0
(-3975 5875);
DISPLAY 0.489362 (-3975 5875);
PAINT SKYBLUE (-3975 5875);
FORCEPROP 1 LAST VALUE 22UF
J 0
(-3975 5975);
DISPLAY 0.489362 (-3975 5975);
PAINT SKYBLUE (-3975 5975);
FORCEPROP 1 LAST PART_NUMBER CH6223MEA01
J 0
(-3975 5775);
DISPLAY 0.489362 (-3975 5775);
PAINT SKYBLUE (-3975 5775);
DISPLAY INVISIBLE (-3975 5775);
FORCEPROP 1 LAST PATH I51
J 0
(-3975 6075);
DISPLAY 0.978723 (-3975 6075);
PAINT WHITE (-3975 6075);
DISPLAY INVISIBLE (-3975 6075);
FORCEPROP 2 LAST CDS_LIB pure_quanta
J 0
(-4025 5925);
DISPLAY INVISIBLE (-4025 5925);
FORCEADD Q_CAP..1
(-3575 2200);
FORCEPROP 1 LAST LOCATION PC594
J 0
(-3525 2325);
DISPLAY 0.489362 (-3525 2325);
PAINT SKYBLUE (-3525 2325);
FORCEPROP 0 LAST $SEC 1
J 0
(-3525 2350);
DISPLAY 0.680851 (-3525 2350);
PAINT MONO (-3525 2350);
DISPLAY INVISIBLE (-3525 2350);
FORCEPROP 0 LAST CDS_SEC 1
J 0
(-3525 2350);
DISPLAY 1.021277 (-3525 2350);
DISPLAY INVISIBLE (-3525 2350);
FORCEPROP 1 LASTPIN (-3575 2300) $PN 1
J 0
(-3565 2280);
DISPLAY 0.489362 (-3565 2280);
PAINT MONO (-3565 2280);
FORCEPROP 1 LASTPIN (-3575 2100) $PN 2
J 0
(-3565 2080);
DISPLAY 0.489362 (-3565 2080);
PAINT MONO (-3565 2080);
FORCEPROP 1 LAST TOLERANCE 10%
J 0
(-3525 2175);
DISPLAY 0.489362 (-3525 2175);
PAINT SKYBLUE (-3525 2175);
FORCEPROP 1 LAST VOLTAGE 16V
J 0
(-3525 2225);
DISPLAY 0.489362 (-3525 2225);
PAINT SKYBLUE (-3525 2225);
FORCEPROP 1 LAST VALUE 0.22UF
J 0
(-3525 2275);
DISPLAY 0.489362 (-3525 2275);
PAINT SKYBLUE (-3525 2275);
FORCEPROP 1 LAST PACK_TYPE 0402
J 0
(-3525 2025);
DISPLAY 0.489362 (-3525 2025);
PAINT SKYBLUE (-3525 2025);
FORCEPROP 1 LAST MATERIAL X7R
J 0
(-3525 2125);
DISPLAY 0.489362 (-3525 2125);
PAINT SKYBLUE (-3525 2125);
FORCEPROP 1 LAST PART_NUMBER CH4223K1B00
J 0
(-3525 2075);
DISPLAY 0.489362 (-3525 2075);
PAINT SKYBLUE (-3525 2075);
DISPLAY INVISIBLE (-3525 2075);
FORCEPROP 1 LAST PATH I52
J 0
(-3525 2350);
DISPLAY 0.978723 (-3525 2350);
PAINT WHITE (-3525 2350);
DISPLAY INVISIBLE (-3525 2350);
FORCEPROP 2 LAST CDS_LIB pure_quanta
J 0
(-3575 2200);
DISPLAY INVISIBLE (-3575 2200);
FORCEADD Q_INDUCTOR4P_14..1
(-2825 1850);
FORCEPROP 1 LAST LOCATION PL64
J 0
(-3050 2105);
DISPLAY 0.489362 (-3050 2105);
PAINT SKYBLUE (-3050 2105);
FORCEPROP 0 LAST $SEC 1
J 0
(-3050 2250);
DISPLAY 0.680851 (-3050 2250);
PAINT MONO (-3050 2250);
DISPLAY INVISIBLE (-3050 2250);
FORCEPROP 0 LAST CDS_SEC 1
J 0
(-3050 2250);
DISPLAY 1.021277 (-3050 2250);
DISPLAY INVISIBLE (-3050 2250);
FORCEPROP 0 LASTPIN (-3225 1975) $PN 1
J 2
(-3235 1985);
DISPLAY 0.489362 (-3235 1985);
PAINT MONO (-3235 1985);
FORCEPROP 0 LASTPIN (-3225 1725) $PN 2
J 2
(-3235 1735);
DISPLAY 0.489362 (-3235 1735);
PAINT MONO (-3235 1735);
FORCEPROP 0 LASTPIN (-2425 1725) $PN 3
J 0
(-2415 1735);
DISPLAY 0.489362 (-2415 1735);
PAINT MONO (-2415 1735);
FORCEPROP 0 LASTPIN (-2425 1975) $PN 4
J 0
(-2415 1985);
DISPLAY 0.489362 (-2415 1985);
PAINT MONO (-2415 1985);
FORCEPROP 2 LAST VALUE 150NH
J 0
(-3050 2150);
DISPLAY 0.489362 (-3050 2150);
PAINT SKYBLUE (-3050 2150);
FORCEPROP 1 LAST MATERIAL IND
J 0
(-3050 2060);
DISPLAY 0.489362 (-3050 2060);
PAINT SKYBLUE (-3050 2060);
FORCEPROP 2 LAST PART_TYPE SMLF
J 0
(-3050 2200);
DISPLAY 1.021277 (-3050 2200);
FORCEPROP 1 LAST PART_NUMBER CV+15^0TZ04
J 0
(-3050 2010);
DISPLAY 0.489362 (-3050 2010);
PAINT SKYBLUE (-3050 2010);
DISPLAY INVISIBLE (-3050 2010);
FORCEPROP 1 LAST PATH I53
J 0
(-2625 2005);
DISPLAY 0.723404 (-2625 2005);
PAINT GREEN (-2625 2005);
DISPLAY INVISIBLE (-2625 2005);
FORCEPROP 1 LAST NEEDS_NO_SIZE TRUE
J 0
(-2825 1850);
DISPLAY 0.468085 (-2825 1850);
PAINT GREEN (-2825 1850);
DISPLAY INVISIBLE (-2825 1850);
FORCEPROP 2 LAST CDS_LIB pure_quanta
J 0
(-2825 1850);
DISPLAY INVISIBLE (-2825 1850);
FORCEADD OFFPAGE..3
(-2000 1725);
FORCEPROP 2 LAST $XR0 198 
J 0
(-1756 1725);
DISPLAY 0.638298 (-1756 1725);
PAINT MONO (-1756 1725);
FORCEPROP 2 LAST PATH I54
J 0
(-1750 1775);
DISPLAY 0.680851 (-1750 1775);
DISPLAY INVISIBLE (-1750 1775);
FORCEPROP 1 LAST COMMENT_BODY TRUE
J 0
(-2050 1625);
DISPLAY 0.872340 (-2050 1625);
PAINT GREEN (-2050 1625);
DISPLAY INVISIBLE (-2050 1625);
FORCEPROP 1 LAST OFFPAGE TRUE
J 0
(-1675 1600);
DISPLAY 0.872340 (-1675 1600);
PAINT GREEN (-1675 1600);
DISPLAY INVISIBLE (-1675 1600);
FORCEPROP 2 LAST CDS_LIB standard
J 0
(-2000 1725);
DISPLAY INVISIBLE (-2000 1725);
FORCEADD UNIVERSAL_GND..1
(-3400 2550);
FORCEPROP 3 LASTPIN (-3400 2600) SIG_NAME GND\g
J 0
(-3390 2610);
DISPLAY 0.659574 (-3390 2610);
PAINT MONO (-3390 2610);
DISPLAY INVISIBLE (-3390 2610);
FORCEPROP 1 LAST PATH I55
J 0
(-3325 2550);
DISPLAY 0.872340 (-3325 2550);
PAINT AQUA (-3325 2550);
DISPLAY INVISIBLE (-3325 2550);
FORCEPROP 1 LAST HDL_POWER GND
J 1
(-3375 2475);
DISPLAY 0.872340 (-3375 2475);
PAINT GREEN (-3375 2475);
DISPLAY INVISIBLE (-3375 2475);
FORCEPROP 2 LAST CDS_LIB pure_quanta_power
J 0
(-3400 2550);
DISPLAY INVISIBLE (-3400 2550);
FORCEADD Q_CAP..1
(-3800 2875);
FORCEPROP 1 LAST LOCATION PC592_2
J 0
(-3750 2975);
DISPLAY 0.489362 (-3750 2975);
PAINT SKYBLUE (-3750 2975);
FORCEPROP 0 LAST $SEC 1
J 0
(-3750 3000);
DISPLAY 0.680851 (-3750 3000);
PAINT MONO (-3750 3000);
DISPLAY INVISIBLE (-3750 3000);
FORCEPROP 0 LAST CDS_SEC 1
J 0
(-3750 3000);
DISPLAY 1.021277 (-3750 3000);
DISPLAY INVISIBLE (-3750 3000);
FORCEPROP 1 LASTPIN (-3800 2975) $PN 1
J 0
(-3790 2955);
DISPLAY 0.489362 (-3790 2955);
PAINT MONO (-3790 2955);
FORCEPROP 1 LASTPIN (-3800 2775) $PN 2
J 0
(-3790 2755);
DISPLAY 0.489362 (-3790 2755);
PAINT MONO (-3790 2755);
FORCEPROP 1 LAST VALUE 22UF
J 0
(-3750 2925);
DISPLAY 0.489362 (-3750 2925);
PAINT SKYBLUE (-3750 2925);
FORCEPROP 1 LAST TOLERANCE 20%
J 0
(-3750 2825);
DISPLAY 0.489362 (-3750 2825);
PAINT SKYBLUE (-3750 2825);
FORCEPROP 1 LAST PACK_TYPE C0805
J 0
(-3750 2675);
DISPLAY 0.489362 (-3750 2675);
PAINT SKYBLUE (-3750 2675);
FORCEPROP 1 LAST MATERIAL X6S
J 0
(-3750 2775);
DISPLAY 0.489362 (-3750 2775);
PAINT SKYBLUE (-3750 2775);
FORCEPROP 1 LAST VOLTAGE 16V
J 0
(-3750 2875);
DISPLAY 0.489362 (-3750 2875);
PAINT SKYBLUE (-3750 2875);
FORCEPROP 1 LAST PART_NUMBER CH6223MEA01
J 0
(-3750 2725);
DISPLAY 0.489362 (-3750 2725);
PAINT SKYBLUE (-3750 2725);
DISPLAY INVISIBLE (-3750 2725);
FORCEPROP 1 LAST PATH I56
J 0
(-3750 3025);
DISPLAY 0.978723 (-3750 3025);
PAINT WHITE (-3750 3025);
DISPLAY INVISIBLE (-3750 3025);
FORCEPROP 2 LAST CDS_LIB pure_quanta
J 0
(-3800 2875);
DISPLAY INVISIBLE (-3800 2875);
FORCEADD Q_CAP..1
(-3400 2875);
FORCEPROP 1 LAST LOCATION PC595_2
J 0
(-3350 2975);
DISPLAY 0.489362 (-3350 2975);
PAINT SKYBLUE (-3350 2975);
FORCEPROP 0 LAST $SEC 1
J 0
(-3350 3000);
DISPLAY 0.680851 (-3350 3000);
PAINT MONO (-3350 3000);
DISPLAY INVISIBLE (-3350 3000);
FORCEPROP 0 LAST CDS_SEC 1
J 0
(-3350 3000);
DISPLAY 0.680851 (-3350 3000);
DISPLAY INVISIBLE (-3350 3000);
FORCEPROP 1 LASTPIN (-3400 2975) $PN 1
J 0
(-3390 2955);
DISPLAY 0.787234 (-3390 2955);
PAINT MONO (-3390 2955);
DISPLAY INVISIBLE (-3390 2955);
FORCEPROP 1 LASTPIN (-3400 2775) $PN 2
J 0
(-3390 2755);
DISPLAY 0.787234 (-3390 2755);
PAINT MONO (-3390 2755);
DISPLAY INVISIBLE (-3390 2755);
FORCEPROP 1 LAST MATERIAL X6S
J 0
(-3350 2775);
DISPLAY 0.489362 (-3350 2775);
PAINT SKYBLUE (-3350 2775);
FORCEPROP 1 LAST PACK_TYPE C0805
J 0
(-3350 2675);
DISPLAY 0.489362 (-3350 2675);
PAINT SKYBLUE (-3350 2675);
FORCEPROP 1 LAST VOLTAGE 16V
J 0
(-3350 2875);
DISPLAY 0.489362 (-3350 2875);
PAINT SKYBLUE (-3350 2875);
FORCEPROP 1 LAST VALUE 22UF
J 0
(-3350 2925);
DISPLAY 0.489362 (-3350 2925);
PAINT SKYBLUE (-3350 2925);
FORCEPROP 1 LAST TOLERANCE 20%
J 0
(-3350 2825);
DISPLAY 0.489362 (-3350 2825);
PAINT SKYBLUE (-3350 2825);
FORCEPROP 1 LAST PART_NUMBER CH6223MEA01
J 0
(-3350 2725);
DISPLAY 0.489362 (-3350 2725);
PAINT SKYBLUE (-3350 2725);
DISPLAY INVISIBLE (-3350 2725);
FORCEPROP 1 LAST PATH I57
J 0
(-3350 3025);
DISPLAY 0.978723 (-3350 3025);
PAINT WHITE (-3350 3025);
DISPLAY INVISIBLE (-3350 3025);
FORCEPROP 2 LAST CDS_LIB pure_quanta
J 0
(-3400 2875);
DISPLAY INVISIBLE (-3400 2875);
FORCEADD VCC_CORE..1
(-3400 3150);
FORCEPROP 3 LASTPIN (-3400 3100) SIG_NAME SW_P12V_AUX_PVDDCR_SOC_P0_FLT\g
J 0
(-3390 3110);
DISPLAY 0.659574 (-3390 3110);
PAINT MONO (-3390 3110);
DISPLAY INVISIBLE (-3390 3110);
FORCEPROP 1 LAST HDL_POWER SW_P12V_AUX_PVDDCR_SOC_P0_FLT
J 1
(-3400 3200);
DISPLAY 0.489362 (-3400 3200);
PAINT GREEN (-3400 3200);
FORCEPROP 1 LAST PATH I58
J 0
(-3350 3175);
DISPLAY 0.872340 (-3350 3175);
PAINT AQUA (-3350 3175);
DISPLAY INVISIBLE (-3350 3175);
FORCEPROP 2 LAST CDS_LIB pure_quanta_power
J 0
(-3400 3150);
DISPLAY INVISIBLE (-3400 3150);
FORCEADD Q_CAP..1
(-1425 1800);
FORCEPROP 1 LAST LOCATION PC600_2
J 0
(-1375 1900);
DISPLAY 0.489362 (-1375 1900);
PAINT SKYBLUE (-1375 1900);
FORCEPROP 0 LAST $SEC 1
J 0
(-1375 1925);
DISPLAY 0.680851 (-1375 1925);
PAINT MONO (-1375 1925);
DISPLAY INVISIBLE (-1375 1925);
FORCEPROP 0 LAST CDS_SEC 1
J 0
(-1375 1925);
DISPLAY 1.021277 (-1375 1925);
DISPLAY INVISIBLE (-1375 1925);
FORCEPROP 1 LASTPIN (-1425 1900) $PN 1
J 0
(-1415 1880);
DISPLAY 0.489362 (-1415 1880);
PAINT MONO (-1415 1880);
FORCEPROP 1 LASTPIN (-1425 1700) $PN 2
J 0
(-1415 1680);
DISPLAY 0.489362 (-1415 1680);
PAINT MONO (-1415 1680);
FORCEPROP 1 LAST TOLERANCE 20%
J 0
(-1375 1750);
DISPLAY 0.489362 (-1375 1750);
PAINT SKYBLUE (-1375 1750);
FORCEPROP 1 LAST PACK_TYPE C0805
J 0
(-1375 1600);
DISPLAY 0.489362 (-1375 1600);
PAINT SKYBLUE (-1375 1600);
FORCEPROP 1 LAST MATERIAL X6S
J 0
(-1375 1700);
DISPLAY 0.489362 (-1375 1700);
PAINT SKYBLUE (-1375 1700);
FORCEPROP 1 LAST VALUE 22UF
J 0
(-1375 1850);
DISPLAY 0.489362 (-1375 1850);
PAINT SKYBLUE (-1375 1850);
FORCEPROP 1 LAST VOLTAGE 4V
J 0
(-1375 1800);
DISPLAY 0.489362 (-1375 1800);
PAINT SKYBLUE (-1375 1800);
FORCEPROP 1 LAST PART_NUMBER CH622KMEA03
J 0
(-1375 1650);
DISPLAY 0.489362 (-1375 1650);
PAINT SKYBLUE (-1375 1650);
DISPLAY INVISIBLE (-1375 1650);
FORCEPROP 1 LAST PATH I59
J 0
(-1375 1950);
DISPLAY 0.978723 (-1375 1950);
PAINT WHITE (-1375 1950);
DISPLAY INVISIBLE (-1375 1950);
FORCEPROP 2 LAST CDS_LIB pure_quanta
J 0
(-1425 1800);
DISPLAY INVISIBLE (-1425 1800);
FORCEADD OFFPAGE..1
(-6900 1375);
FORCEPROP 2 LAST $XR0 193 
J 0
(-7182 1375);
DISPLAY 0.638298 (-7182 1375);
PAINT MONO (-7182 1375);
FORCEPROP 2 LAST PATH I6
J 0
(-7150 1425);
DISPLAY 0.680851 (-7150 1425);
DISPLAY INVISIBLE (-7150 1425);
FORCEPROP 1 LAST COMMENT_BODY TRUE
J 0
(-6775 1275);
DISPLAY 0.872340 (-6775 1275);
PAINT GREEN (-6775 1275);
DISPLAY INVISIBLE (-6775 1275);
FORCEPROP 1 LAST OFFPAGE TRUE
J 0
(-6575 1250);
DISPLAY 0.872340 (-6575 1250);
PAINT GREEN (-6575 1250);
DISPLAY INVISIBLE (-6575 1250);
FORCEPROP 2 LAST CDS_LIB standard
J 2
(-6900 1375);
DISPLAY INVISIBLE (-6900 1375);
FORCEADD UNIVERSAL_GND..1
(-1000 1450);
FORCEPROP 3 LASTPIN (-1000 1500) SIG_NAME GND\g
J 0
(-990 1510);
DISPLAY 0.659574 (-990 1510);
PAINT MONO (-990 1510);
DISPLAY INVISIBLE (-990 1510);
FORCEPROP 1 LAST PATH I60
J 0
(-925 1450);
DISPLAY 0.872340 (-925 1450);
PAINT AQUA (-925 1450);
DISPLAY INVISIBLE (-925 1450);
FORCEPROP 1 LAST HDL_POWER GND
J 1
(-975 1375);
DISPLAY 0.872340 (-975 1375);
PAINT GREEN (-975 1375);
DISPLAY INVISIBLE (-975 1375);
FORCEPROP 2 LAST CDS_LIB pure_quanta_power
J 0
(-1000 1450);
DISPLAY INVISIBLE (-1000 1450);
FORCEADD Q_CAP..1
(-1000 1800);
FORCEPROP 1 LAST LOCATION PC603_2
J 0
(-950 1900);
DISPLAY 0.489362 (-950 1900);
PAINT SKYBLUE (-950 1900);
FORCEPROP 0 LAST $SEC 1
J 0
(-950 1925);
DISPLAY 0.680851 (-950 1925);
PAINT MONO (-950 1925);
DISPLAY INVISIBLE (-950 1925);
FORCEPROP 0 LAST CDS_SEC 1
J 0
(-950 1925);
DISPLAY 1.021277 (-950 1925);
DISPLAY INVISIBLE (-950 1925);
FORCEPROP 1 LASTPIN (-1000 1900) $PN 1
J 0
(-990 1880);
DISPLAY 0.489362 (-990 1880);
PAINT MONO (-990 1880);
FORCEPROP 1 LASTPIN (-1000 1700) $PN 2
J 0
(-990 1680);
DISPLAY 0.489362 (-990 1680);
PAINT MONO (-990 1680);
FORCEPROP 1 LAST TOLERANCE 20%
J 0
(-950 1750);
DISPLAY 0.489362 (-950 1750);
PAINT SKYBLUE (-950 1750);
FORCEPROP 1 LAST PACK_TYPE C0805
J 0
(-950 1600);
DISPLAY 0.489362 (-950 1600);
PAINT SKYBLUE (-950 1600);
FORCEPROP 1 LAST MATERIAL X6S
J 0
(-950 1700);
DISPLAY 0.489362 (-950 1700);
PAINT SKYBLUE (-950 1700);
FORCEPROP 1 LAST VALUE 22UF
J 0
(-950 1850);
DISPLAY 0.489362 (-950 1850);
PAINT SKYBLUE (-950 1850);
FORCEPROP 1 LAST VOLTAGE 4V
J 0
(-950 1800);
DISPLAY 0.489362 (-950 1800);
PAINT SKYBLUE (-950 1800);
FORCEPROP 1 LAST PART_NUMBER CH622KMEA03
J 0
(-950 1650);
DISPLAY 0.489362 (-950 1650);
PAINT SKYBLUE (-950 1650);
DISPLAY INVISIBLE (-950 1650);
FORCEPROP 1 LAST PATH I61
J 0
(-950 1950);
DISPLAY 0.978723 (-950 1950);
PAINT WHITE (-950 1950);
DISPLAY INVISIBLE (-950 1950);
FORCEPROP 2 LAST CDS_LIB pure_quanta
J 0
(-1000 1800);
DISPLAY INVISIBLE (-1000 1800);
FORCEADD VCC_CORE..1
(-1000 2125);
FORCEPROP 3 LASTPIN (-1000 2075) SIG_NAME PVDDCR_SOC_P0\g
J 0
(-990 2085);
DISPLAY 0.659574 (-990 2085);
PAINT MONO (-990 2085);
DISPLAY INVISIBLE (-990 2085);
FORCEPROP 1 LAST HDL_POWER PVDDCR_SOC_P0
J 1
(-1000 2175);
DISPLAY 0.489362 (-1000 2175);
PAINT GREEN (-1000 2175);
FORCEPROP 1 LAST PATH I62
J 0
(-950 2150);
DISPLAY 0.872340 (-950 2150);
PAINT AQUA (-950 2150);
DISPLAY INVISIBLE (-950 2150);
FORCEPROP 2 LAST CDS_LIB pure_quanta_power
J 0
(-1000 2125);
DISPLAY INVISIBLE (-1000 2125);
FORCEADD Q_CAPP..1
(-1625 3250);
FORCEPROP 1 LAST LOCATION PC597
J 0
(-1575 3350);
DISPLAY 0.489362 (-1575 3350);
PAINT SKYBLUE (-1575 3350);
FORCEPROP 0 LAST $SEC 1
J 0
(-1575 3375);
DISPLAY 0.680851 (-1575 3375);
PAINT MONO (-1575 3375);
DISPLAY INVISIBLE (-1575 3375);
FORCEPROP 0 LAST CDS_SEC 1
J 0
(-1575 3375);
DISPLAY 1.021277 (-1575 3375);
DISPLAY INVISIBLE (-1575 3375);
FORCEPROP 1 LASTPIN (-1625 3350) $PN 1
J 0
(-1615 3335);
DISPLAY 0.489362 (-1615 3335);
PAINT MONO (-1615 3335);
FORCEPROP 1 LASTPIN (-1625 3150) $PN 2
J 0
(-1615 3135);
DISPLAY 0.489362 (-1615 3135);
PAINT MONO (-1615 3135);
FORCEPROP 1 LAST PACK_TYPE SMLF
J 0
(-1575 3100);
DISPLAY 0.489362 (-1575 3100);
PAINT SKYBLUE (-1575 3100);
FORCEPROP 1 LAST VOLTAGE 2.5V
J 0
(-1575 3200);
DISPLAY 0.489362 (-1575 3200);
PAINT SKYBLUE (-1575 3200);
FORCEPROP 1 LAST TOLERANCE 20%
J 0
(-1575 3250);
DISPLAY 0.489362 (-1575 3250);
PAINT SKYBLUE (-1575 3250);
FORCEPROP 1 LAST MATERIAL EMPTY
J 0
(-1575 3150);
DISPLAY 0.489362 (-1575 3150);
PAINT RED (-1575 3150);
FORCEPROP 1 LAST VALUE 470UF
J 0
(-1575 3300);
DISPLAY 0.489362 (-1575 3300);
PAINT SKYBLUE (-1575 3300);
FORCEPROP 1 LAST PART_NUMBER CH747LM8825
J 0
(-1575 3050);
DISPLAY 0.489362 (-1575 3050);
PAINT SKYBLUE (-1575 3050);
DISPLAY INVISIBLE (-1575 3050);
FORCEPROP 1 LAST PATH I63
J 0
(-1575 3400);
DISPLAY 0.978723 (-1575 3400);
DISPLAY INVISIBLE (-1575 3400);
FORCEPROP 2 LAST CDS_LIB pure_quanta
J 0
(-1625 3250);
DISPLAY INVISIBLE (-1625 3250);
FORCEADD Q_CAPP..1
(-1275 3250);
FORCEPROP 1 LAST LOCATION PC598
J 0
(-1225 3350);
DISPLAY 0.489362 (-1225 3350);
PAINT SKYBLUE (-1225 3350);
FORCEPROP 0 LAST $SEC 1
J 0
(-1225 3375);
DISPLAY 0.680851 (-1225 3375);
PAINT MONO (-1225 3375);
DISPLAY INVISIBLE (-1225 3375);
FORCEPROP 0 LAST CDS_SEC 1
J 0
(-1225 3375);
DISPLAY 1.021277 (-1225 3375);
DISPLAY INVISIBLE (-1225 3375);
FORCEPROP 1 LASTPIN (-1275 3350) $PN 1
J 0
(-1265 3335);
DISPLAY 0.489362 (-1265 3335);
PAINT MONO (-1265 3335);
FORCEPROP 1 LASTPIN (-1275 3150) $PN 2
J 0
(-1265 3135);
DISPLAY 0.489362 (-1265 3135);
PAINT MONO (-1265 3135);
FORCEPROP 1 LAST PACK_TYPE SMLF
J 0
(-1225 3100);
DISPLAY 0.489362 (-1225 3100);
PAINT SKYBLUE (-1225 3100);
FORCEPROP 1 LAST MATERIAL SPCAP
J 0
(-1225 3150);
DISPLAY 0.489362 (-1225 3150);
PAINT SKYBLUE (-1225 3150);
FORCEPROP 1 LAST TOLERANCE 20%
J 0
(-1225 3250);
DISPLAY 0.489362 (-1225 3250);
PAINT SKYBLUE (-1225 3250);
FORCEPROP 1 LAST VOLTAGE 2.5V
J 0
(-1225 3200);
DISPLAY 0.489362 (-1225 3200);
PAINT SKYBLUE (-1225 3200);
FORCEPROP 1 LAST VALUE 470UF
J 0
(-1225 3300);
DISPLAY 0.489362 (-1225 3300);
PAINT SKYBLUE (-1225 3300);
FORCEPROP 1 LAST PART_NUMBER CH747LM8825
J 0
(-1225 3050);
DISPLAY 0.489362 (-1225 3050);
PAINT SKYBLUE (-1225 3050);
DISPLAY INVISIBLE (-1225 3050);
FORCEPROP 1 LAST PATH I64
J 0
(-1225 3400);
DISPLAY 0.978723 (-1225 3400);
DISPLAY INVISIBLE (-1225 3400);
FORCEPROP 2 LAST CDS_LIB pure_quanta
J 0
(-1275 3250);
DISPLAY INVISIBLE (-1275 3250);
FORCEADD UNIVERSAL_GND..1
(-950 2900);
FORCEPROP 3 LASTPIN (-950 2950) SIG_NAME GND\g
J 0
(-940 2960);
DISPLAY 0.659574 (-940 2960);
PAINT MONO (-940 2960);
DISPLAY INVISIBLE (-940 2960);
FORCEPROP 1 LAST PATH I65
J 0
(-875 2900);
DISPLAY 0.872340 (-875 2900);
PAINT AQUA (-875 2900);
DISPLAY INVISIBLE (-875 2900);
FORCEPROP 1 LAST HDL_POWER GND
J 1
(-925 2825);
DISPLAY 0.872340 (-925 2825);
PAINT GREEN (-925 2825);
DISPLAY INVISIBLE (-925 2825);
FORCEPROP 2 LAST CDS_LIB pure_quanta_power
J 0
(-950 2900);
DISPLAY INVISIBLE (-950 2900);
FORCEADD Q_CAPP..1
(-950 3250);
FORCEPROP 1 LAST LOCATION PC601
J 0
(-900 3350);
DISPLAY 0.489362 (-900 3350);
PAINT SKYBLUE (-900 3350);
FORCEPROP 0 LAST $SEC 1
J 0
(-900 3400);
DISPLAY 0.680851 (-900 3400);
PAINT MONO (-900 3400);
DISPLAY INVISIBLE (-900 3400);
FORCEPROP 0 LAST CDS_SEC 1
J 0
(-900 3400);
DISPLAY 1.021277 (-900 3400);
DISPLAY INVISIBLE (-900 3400);
FORCEPROP 1 LASTPIN (-950 3350) $PN 1
J 0
(-940 3335);
DISPLAY 0.489362 (-940 3335);
PAINT MONO (-940 3335);
FORCEPROP 1 LASTPIN (-950 3150) $PN 2
J 0
(-940 3135);
DISPLAY 0.489362 (-940 3135);
PAINT MONO (-940 3135);
FORCEPROP 1 LAST PACK_TYPE SMLF
J 0
(-900 3100);
DISPLAY 0.489362 (-900 3100);
PAINT SKYBLUE (-900 3100);
FORCEPROP 1 LAST VOLTAGE 2.5V
J 0
(-900 3200);
DISPLAY 0.489362 (-900 3200);
PAINT SKYBLUE (-900 3200);
FORCEPROP 1 LAST VALUE 470UF
J 0
(-900 3300);
DISPLAY 0.489362 (-900 3300);
PAINT SKYBLUE (-900 3300);
FORCEPROP 1 LAST TOLERANCE 20%
J 0
(-900 3250);
DISPLAY 0.489362 (-900 3250);
PAINT SKYBLUE (-900 3250);
FORCEPROP 1 LAST MATERIAL SPCAP
J 0
(-900 3150);
DISPLAY 0.489362 (-900 3150);
PAINT SKYBLUE (-900 3150);
FORCEPROP 1 LAST PART_NUMBER CH747LM8825
J 0
(-900 3050);
DISPLAY 0.489362 (-900 3050);
PAINT SKYBLUE (-900 3050);
DISPLAY INVISIBLE (-900 3050);
FORCEPROP 1 LAST PATH I66
J 0
(-900 3400);
DISPLAY 0.978723 (-900 3400);
DISPLAY INVISIBLE (-900 3400);
FORCEPROP 2 LAST CDS_LIB pure_quanta
J 0
(-950 3250);
DISPLAY INVISIBLE (-950 3250);
FORCEADD VCC_CORE..1
(-950 3525);
FORCEPROP 3 LASTPIN (-950 3475) SIG_NAME PVDDCR_SOC_P0\g
J 0
(-940 3485);
DISPLAY 0.659574 (-940 3485);
PAINT MONO (-940 3485);
DISPLAY INVISIBLE (-940 3485);
FORCEPROP 1 LAST HDL_POWER PVDDCR_SOC_P0
J 1
(-950 3575);
DISPLAY 0.489362 (-950 3575);
PAINT GREEN (-950 3575);
FORCEPROP 1 LAST PATH I67
J 0
(-900 3550);
DISPLAY 0.872340 (-900 3550);
PAINT AQUA (-900 3550);
DISPLAY INVISIBLE (-900 3550);
FORCEPROP 2 LAST CDS_LIB pure_quanta_power
J 0
(-950 3525);
DISPLAY INVISIBLE (-950 3525);
FORCEADD Q_CAP..1
(-3675 5300);
FORCEPROP 1 LAST LOCATION PC593
J 0
(-3625 5425);
DISPLAY 0.489362 (-3625 5425);
PAINT SKYBLUE (-3625 5425);
FORCEPROP 0 LAST $SEC 1
J 0
(-3625 5450);
DISPLAY 0.680851 (-3625 5450);
PAINT MONO (-3625 5450);
DISPLAY INVISIBLE (-3625 5450);
FORCEPROP 0 LAST CDS_SEC 1
J 0
(-3625 5450);
DISPLAY 1.021277 (-3625 5450);
DISPLAY INVISIBLE (-3625 5450);
FORCEPROP 1 LASTPIN (-3675 5400) $PN 1
J 0
(-3665 5380);
DISPLAY 0.489362 (-3665 5380);
PAINT MONO (-3665 5380);
FORCEPROP 1 LASTPIN (-3675 5200) $PN 2
J 0
(-3665 5180);
DISPLAY 0.489362 (-3665 5180);
PAINT MONO (-3665 5180);
FORCEPROP 1 LAST PACK_TYPE 0402
J 0
(-3625 5125);
DISPLAY 0.489362 (-3625 5125);
PAINT SKYBLUE (-3625 5125);
FORCEPROP 1 LAST VALUE 0.22UF
J 0
(-3625 5375);
DISPLAY 0.489362 (-3625 5375);
PAINT SKYBLUE (-3625 5375);
FORCEPROP 1 LAST VOLTAGE 16V
J 0
(-3625 5325);
DISPLAY 0.489362 (-3625 5325);
PAINT SKYBLUE (-3625 5325);
FORCEPROP 1 LAST TOLERANCE 10%
J 0
(-3625 5275);
DISPLAY 0.489362 (-3625 5275);
PAINT SKYBLUE (-3625 5275);
FORCEPROP 1 LAST MATERIAL X7R
J 0
(-3625 5225);
DISPLAY 0.489362 (-3625 5225);
PAINT SKYBLUE (-3625 5225);
FORCEPROP 1 LAST PART_NUMBER CH4223K1B00
J 0
(-3625 5175);
DISPLAY 0.489362 (-3625 5175);
PAINT SKYBLUE (-3625 5175);
DISPLAY INVISIBLE (-3625 5175);
FORCEPROP 1 LAST PATH I68
J 0
(-3625 5450);
DISPLAY 0.978723 (-3625 5450);
PAINT WHITE (-3625 5450);
DISPLAY INVISIBLE (-3625 5450);
FORCEPROP 2 LAST CDS_LIB pure_quanta
J 0
(-3675 5300);
DISPLAY INVISIBLE (-3675 5300);
FORCEADD Q_INDUCTOR4P_14..1
(-2900 4950);
FORCEPROP 1 LAST LOCATION PL63
J 0
(-3125 5205);
DISPLAY 0.489362 (-3125 5205);
PAINT SKYBLUE (-3125 5205);
FORCEPROP 0 LAST $SEC 1
J 0
(-3125 5350);
DISPLAY 0.680851 (-3125 5350);
PAINT MONO (-3125 5350);
DISPLAY INVISIBLE (-3125 5350);
FORCEPROP 0 LAST CDS_SEC 1
J 0
(-3125 5350);
DISPLAY 1.021277 (-3125 5350);
DISPLAY INVISIBLE (-3125 5350);
FORCEPROP 0 LASTPIN (-3300 5075) $PN 1
J 2
(-3310 5085);
DISPLAY 0.489362 (-3310 5085);
PAINT MONO (-3310 5085);
FORCEPROP 0 LASTPIN (-3300 4825) $PN 2
J 2
(-3310 4835);
DISPLAY 0.489362 (-3310 4835);
PAINT MONO (-3310 4835);
FORCEPROP 0 LASTPIN (-2500 4825) $PN 3
J 0
(-2490 4835);
DISPLAY 0.489362 (-2490 4835);
PAINT MONO (-2490 4835);
FORCEPROP 0 LASTPIN (-2500 5075) $PN 4
J 0
(-2490 5085);
DISPLAY 0.489362 (-2490 5085);
PAINT MONO (-2490 5085);
FORCEPROP 1 LAST MATERIAL IND
J 0
(-3125 5160);
DISPLAY 0.489362 (-3125 5160);
PAINT SKYBLUE (-3125 5160);
FORCEPROP 2 LAST PART_TYPE SMLF
J 0
(-3125 5300);
DISPLAY 1.021277 (-3125 5300);
FORCEPROP 2 LAST VALUE 150NH
J 0
(-3125 5250);
DISPLAY 0.489362 (-3125 5250);
PAINT SKYBLUE (-3125 5250);
FORCEPROP 1 LAST PART_NUMBER CV+15^0TZ04
J 0
(-3125 5110);
DISPLAY 0.489362 (-3125 5110);
PAINT SKYBLUE (-3125 5110);
DISPLAY INVISIBLE (-3125 5110);
FORCEPROP 1 LAST PATH I69
J 0
(-2700 5105);
DISPLAY 0.723404 (-2700 5105);
PAINT GREEN (-2700 5105);
DISPLAY INVISIBLE (-2700 5105);
FORCEPROP 1 LAST NEEDS_NO_SIZE TRUE
J 0
(-2900 4950);
DISPLAY 0.468085 (-2900 4950);
PAINT GREEN (-2900 4950);
DISPLAY INVISIBLE (-2900 4950);
FORCEPROP 2 LAST CDS_LIB pure_quanta
J 0
(-2900 4950);
DISPLAY INVISIBLE (-2900 4950);
FORCEADD OFFPAGE..2
R 2
(-6925 1475);
FORCEPROP 2 LAST $XR0 198 
J 0
(-7180 1475);
DISPLAY 0.638298 (-7180 1475);
PAINT MONO (-7180 1475);
FORCEPROP 2 LAST $XR1 199 
J 0
(-7180 1439);
DISPLAY 0.638298 (-7180 1439);
PAINT MONO (-7180 1439);
FORCEPROP 2 LAST $XR2 193 
J 0
(-7300 1439);
DISPLAY 0.638298 (-7300 1439);
PAINT MONO (-7300 1439);
FORCEPROP 2 LAST PATH I7
J 0
(-7175 1525);
DISPLAY 0.680851 (-7175 1525);
DISPLAY INVISIBLE (-7175 1525);
FORCEPROP 1 LAST COMMENT_BODY TRUE
J 2
(-6880 1380);
DISPLAY 0.872340 (-6880 1380);
PAINT GREEN (-6880 1380);
DISPLAY INVISIBLE (-6880 1380);
FORCEPROP 1 LAST OFFPAGE TRUE
J 2
(-7250 1350);
DISPLAY 0.872340 (-7250 1350);
PAINT GREEN (-7250 1350);
DISPLAY INVISIBLE (-7250 1350);
FORCEPROP 2 LAST CDS_LIB standard
J 0
(-6925 1475);
DISPLAY INVISIBLE (-6925 1475);
FORCEADD UNIVERSAL_GND..1
(-3675 5600);
FORCEPROP 3 LASTPIN (-3675 5650) SIG_NAME GND\g
J 0
(-3665 5660);
DISPLAY 0.659574 (-3665 5660);
PAINT MONO (-3665 5660);
DISPLAY INVISIBLE (-3665 5660);
FORCEPROP 1 LAST PATH I70
J 0
(-3600 5600);
DISPLAY 0.872340 (-3600 5600);
PAINT AQUA (-3600 5600);
DISPLAY INVISIBLE (-3600 5600);
FORCEPROP 1 LAST HDL_POWER GND
J 1
(-3650 5525);
DISPLAY 0.872340 (-3650 5525);
PAINT GREEN (-3650 5525);
DISPLAY INVISIBLE (-3650 5525);
FORCEPROP 2 LAST CDS_LIB pure_quanta_power
J 0
(-3675 5600);
DISPLAY INVISIBLE (-3675 5600);
FORCEADD VCC_CORE..1
(-3675 6200);
FORCEPROP 3 LASTPIN (-3675 6150) SIG_NAME SW_P12V_AUX_PVDDCR_SOC_P0_FLT\g
J 0
(-3665 6160);
DISPLAY 0.659574 (-3665 6160);
PAINT MONO (-3665 6160);
DISPLAY INVISIBLE (-3665 6160);
FORCEPROP 1 LAST HDL_POWER SW_P12V_AUX_PVDDCR_SOC_P0_FLT
J 1
(-3675 6250);
DISPLAY 0.489362 (-3675 6250);
PAINT GREEN (-3675 6250);
FORCEPROP 1 LAST PATH I71
J 0
(-3625 6225);
DISPLAY 0.872340 (-3625 6225);
PAINT AQUA (-3625 6225);
DISPLAY INVISIBLE (-3625 6225);
FORCEPROP 2 LAST CDS_LIB pure_quanta_power
J 0
(-3675 6200);
DISPLAY INVISIBLE (-3675 6200);
FORCEADD Q_CAP..1
(-3800 5925);
FORCEPROP 1 LAST LOCATION PC593_1
J 0
(-3750 6025);
DISPLAY 0.489362 (-3750 6025);
PAINT SKYBLUE (-3750 6025);
FORCEPROP 0 LAST $SEC 1
J 0
(-3750 6050);
DISPLAY 0.680851 (-3750 6050);
PAINT MONO (-3750 6050);
DISPLAY INVISIBLE (-3750 6050);
FORCEPROP 0 LAST CDS_SEC 1
J 0
(-3750 6050);
DISPLAY 0.680851 (-3750 6050);
DISPLAY INVISIBLE (-3750 6050);
FORCEPROP 1 LASTPIN (-3800 6025) $PN 1
J 0
(-3790 6005);
DISPLAY 0.787234 (-3790 6005);
PAINT MONO (-3790 6005);
DISPLAY INVISIBLE (-3790 6005);
FORCEPROP 1 LASTPIN (-3800 5825) $PN 2
J 0
(-3790 5805);
DISPLAY 0.787234 (-3790 5805);
PAINT MONO (-3790 5805);
DISPLAY INVISIBLE (-3790 5805);
FORCEPROP 1 LAST VALUE 22UF
J 0
(-3750 5975);
DISPLAY 0.489362 (-3750 5975);
PAINT SKYBLUE (-3750 5975);
FORCEPROP 1 LAST TOLERANCE 20%
J 0
(-3750 5875);
DISPLAY 0.489362 (-3750 5875);
PAINT SKYBLUE (-3750 5875);
FORCEPROP 1 LAST VOLTAGE 16V
J 0
(-3750 5925);
DISPLAY 0.489362 (-3750 5925);
PAINT SKYBLUE (-3750 5925);
FORCEPROP 1 LAST PACK_TYPE C0805
J 0
(-3750 5725);
DISPLAY 0.489362 (-3750 5725);
PAINT SKYBLUE (-3750 5725);
FORCEPROP 1 LAST MATERIAL X6S
J 0
(-3750 5825);
DISPLAY 0.489362 (-3750 5825);
PAINT SKYBLUE (-3750 5825);
FORCEPROP 1 LAST PART_NUMBER CH6223MEA01
J 0
(-3750 5775);
DISPLAY 0.489362 (-3750 5775);
PAINT SKYBLUE (-3750 5775);
DISPLAY INVISIBLE (-3750 5775);
FORCEPROP 1 LAST PATH I72
J 0
(-3750 6075);
DISPLAY 0.978723 (-3750 6075);
PAINT WHITE (-3750 6075);
DISPLAY INVISIBLE (-3750 6075);
FORCEPROP 2 LAST CDS_LIB pure_quanta
J 0
(-3800 5925);
DISPLAY INVISIBLE (-3800 5925);
FORCEADD Q_CAPP..1
(-3225 5925);
FORCEPROP 1 LAST LOCATION PC596
J 0
(-3175 6025);
DISPLAY 0.489362 (-3175 6025);
PAINT SKYBLUE (-3175 6025);
FORCEPROP 0 LAST $SEC 1
J 0
(-3175 6075);
DISPLAY 0.680851 (-3175 6075);
PAINT MONO (-3175 6075);
DISPLAY INVISIBLE (-3175 6075);
FORCEPROP 0 LAST CDS_SEC 1
J 0
(-3175 6075);
DISPLAY 1.021277 (-3175 6075);
DISPLAY INVISIBLE (-3175 6075);
FORCEPROP 1 LASTPIN (-3225 6025) $PN 1
J 0
(-3215 6010);
DISPLAY 0.489362 (-3215 6010);
PAINT MONO (-3215 6010);
FORCEPROP 1 LASTPIN (-3225 5825) $PN 2
J 0
(-3215 5810);
DISPLAY 0.489362 (-3215 5810);
PAINT MONO (-3215 5810);
FORCEPROP 1 LAST TOLERANCE 20%
J 0
(-3175 5925);
DISPLAY 0.489362 (-3175 5925);
PAINT SKYBLUE (-3175 5925);
FORCEPROP 1 LAST VALUE 270UF
J 0
(-3175 5975);
DISPLAY 0.489362 (-3175 5975);
PAINT SKYBLUE (-3175 5975);
FORCEPROP 1 LAST MATERIAL OSCON
J 0
(-3175 5825);
DISPLAY 0.489362 (-3175 5825);
PAINT SKYBLUE (-3175 5825);
FORCEPROP 1 LAST PACK_TYPE THLF
J 0
(-3175 5775);
DISPLAY 0.489362 (-3175 5775);
PAINT SKYBLUE (-3175 5775);
FORCEPROP 1 LAST VOLTAGE 16V
J 0
(-3175 5875);
DISPLAY 0.489362 (-3175 5875);
PAINT SKYBLUE (-3175 5875);
FORCEPROP 1 LAST PART_NUMBER CC72703MD38
J 0
(-3175 5725);
DISPLAY 0.489362 (-3175 5725);
PAINT SKYBLUE (-3175 5725);
DISPLAY INVISIBLE (-3175 5725);
FORCEPROP 1 LAST PATH I73
J 0
(-3175 6075);
DISPLAY 0.978723 (-3175 6075);
DISPLAY INVISIBLE (-3175 6075);
FORCEPROP 2 LAST CDS_LIB pure_quanta
J 0
(-3225 5925);
DISPLAY INVISIBLE (-3225 5925);
FORCEADD Q_INDUCTOR..1
(-2775 6125);
FORCEPROP 1 LAST LOCATION PL65
J 0
(-2900 6285);
DISPLAY 0.489362 (-2900 6285);
PAINT SKYBLUE (-2900 6285);
FORCEPROP 0 LAST $SEC 1
J 0
(-2900 6400);
DISPLAY 0.680851 (-2900 6400);
PAINT MONO (-2900 6400);
DISPLAY INVISIBLE (-2900 6400);
FORCEPROP 0 LAST CDS_SEC 1
J 0
(-2900 6400);
DISPLAY 1.021277 (-2900 6400);
DISPLAY INVISIBLE (-2900 6400);
FORCEPROP 0 LASTPIN (-2875 6100) $PN 1
J 2
(-2885 6110);
DISPLAY 0.489362 (-2885 6110);
PAINT MONO (-2885 6110);
FORCEPROP 0 LASTPIN (-2675 6100) $PN 2
J 0
(-2665 6110);
DISPLAY 0.489362 (-2665 6110);
PAINT MONO (-2665 6110);
FORCEPROP 1 LAST MATERIAL IND
J 0
(-2900 6180);
DISPLAY 0.489362 (-2900 6180);
PAINT SKYBLUE (-2900 6180);
FORCEPROP 2 LAST VALUE 50NH/86A
J 0
(-2900 6375);
DISPLAY 0.489362 (-2900 6375);
PAINT SKYBLUE (-2900 6375);
FORCEPROP 2 LAST PACK_TYPE SMLF
J 0
(-2900 6325);
DISPLAY 0.489362 (-2900 6325);
PAINT SKYBLUE (-2900 6325);
FORCEPROP 1 LAST PART_NUMBER CVA50^0MZ09
J 0
(-2900 6235);
DISPLAY 0.489362 (-2900 6235);
PAINT SKYBLUE (-2900 6235);
DISPLAY INVISIBLE (-2900 6235);
FORCEPROP 1 LAST PATH I74
J 0
(-2700 6180);
DISPLAY 0.723404 (-2700 6180);
PAINT GREEN (-2700 6180);
DISPLAY INVISIBLE (-2700 6180);
FORCEPROP 1 LAST NEEDS_NO_SIZE TRUE
J 0
(-2775 6125);
DISPLAY 0.468085 (-2775 6125);
PAINT GREEN (-2775 6125);
DISPLAY INVISIBLE (-2775 6125);
FORCEPROP 2 LAST CDS_LIB pure_quanta
J 0
(-2775 6125);
DISPLAY INVISIBLE (-2775 6125);
FORCEADD UNIVERSAL_GND..1
(-2025 4675);
FORCEPROP 3 LASTPIN (-2025 4725) SIG_NAME GND\g
J 0
(-2015 4735);
DISPLAY 0.659574 (-2015 4735);
PAINT MONO (-2015 4735);
DISPLAY INVISIBLE (-2015 4735);
FORCEPROP 1 LAST PATH I75
J 0
(-1950 4675);
DISPLAY 0.872340 (-1950 4675);
PAINT AQUA (-1950 4675);
DISPLAY INVISIBLE (-1950 4675);
FORCEPROP 1 LAST HDL_POWER GND
J 1
(-2000 4600);
DISPLAY 0.872340 (-2000 4600);
PAINT GREEN (-2000 4600);
DISPLAY INVISIBLE (-2000 4600);
FORCEPROP 2 LAST CDS_LIB pure_quanta_power
J 0
(-2025 4675);
DISPLAY INVISIBLE (-2025 4675);
FORCEADD UNIVERSAL_GND..1
(-2375 5625);
FORCEPROP 3 LASTPIN (-2375 5675) SIG_NAME GND\g
J 0
(-2365 5685);
DISPLAY 0.659574 (-2365 5685);
PAINT MONO (-2365 5685);
DISPLAY INVISIBLE (-2365 5685);
FORCEPROP 1 LAST PATH I76
J 0
(-2300 5625);
DISPLAY 0.872340 (-2300 5625);
PAINT AQUA (-2300 5625);
DISPLAY INVISIBLE (-2300 5625);
FORCEPROP 1 LAST HDL_POWER GND
J 1
(-2350 5550);
DISPLAY 0.872340 (-2350 5550);
PAINT GREEN (-2350 5550);
DISPLAY INVISIBLE (-2350 5550);
FORCEPROP 2 LAST CDS_LIB pure_quanta_power
J 0
(-2375 5625);
DISPLAY INVISIBLE (-2375 5625);
FORCEADD Q_CAP..1
(-2375 5950);
FORCEPROP 1 LAST LOCATION PC583
J 0
(-2325 6050);
DISPLAY 0.489362 (-2325 6050);
PAINT SKYBLUE (-2325 6050);
FORCEPROP 0 LAST $SEC 1
J 0
(-2325 6075);
DISPLAY 0.680851 (-2325 6075);
PAINT MONO (-2325 6075);
DISPLAY INVISIBLE (-2325 6075);
FORCEPROP 0 LAST CDS_SEC 1
J 0
(-2325 6075);
DISPLAY 0.680851 (-2325 6075);
DISPLAY INVISIBLE (-2325 6075);
FORCEPROP 1 LASTPIN (-2375 6050) $PN 1
J 0
(-2365 6030);
DISPLAY 0.787234 (-2365 6030);
PAINT MONO (-2365 6030);
FORCEPROP 1 LASTPIN (-2375 5850) $PN 2
J 0
(-2365 5830);
DISPLAY 0.787234 (-2365 5830);
PAINT MONO (-2365 5830);
FORCEPROP 1 LAST VOLTAGE 25V
J 0
(-2325 5950);
DISPLAY 0.489362 (-2325 5950);
PAINT SKYBLUE (-2325 5950);
FORCEPROP 1 LAST TOLERANCE 10%
J 0
(-2325 5900);
DISPLAY 0.489362 (-2325 5900);
PAINT SKYBLUE (-2325 5900);
FORCEPROP 1 LAST MATERIAL X7R
J 0
(-2325 5850);
DISPLAY 0.489362 (-2325 5850);
PAINT SKYBLUE (-2325 5850);
FORCEPROP 1 LAST PACK_TYPE 0402
J 0
(-2325 5750);
DISPLAY 0.489362 (-2325 5750);
PAINT SKYBLUE (-2325 5750);
FORCEPROP 1 LAST VALUE 0.1UF
J 0
(-2325 6000);
DISPLAY 0.489362 (-2325 6000);
PAINT SKYBLUE (-2325 6000);
FORCEPROP 1 LAST PART_NUMBER CH4104K1B00
J 0
(-2325 5800);
DISPLAY 0.489362 (-2325 5800);
PAINT SKYBLUE (-2325 5800);
DISPLAY INVISIBLE (-2325 5800);
FORCEPROP 1 LAST PATH I77
J 0
(-2325 6100);
DISPLAY 0.978723 (-2325 6100);
PAINT WHITE (-2325 6100);
DISPLAY INVISIBLE (-2325 6100);
FORCEPROP 2 LAST CDS_LIB pure_quanta
J 0
(-2375 5950);
DISPLAY INVISIBLE (-2375 5950);
FORCEADD VCC_CORE..1
(-2375 6200);
FORCEPROP 3 LASTPIN (-2375 6150) SIG_NAME P12V_AUX\g
J 0
(-2365 6160);
DISPLAY 0.659574 (-2365 6160);
PAINT MONO (-2365 6160);
DISPLAY INVISIBLE (-2365 6160);
FORCEPROP 1 LAST HDL_POWER P12V_AUX
J 1
(-2375 6250);
DISPLAY 0.489362 (-2375 6250);
PAINT GREEN (-2375 6250);
FORCEPROP 1 LAST PATH I78
J 0
(-2325 6225);
DISPLAY 0.872340 (-2325 6225);
PAINT AQUA (-2325 6225);
DISPLAY INVISIBLE (-2325 6225);
FORCEPROP 2 LAST CDS_LIB pure_quanta_power
J 0
(-2375 6200);
DISPLAY INVISIBLE (-2375 6200);
FORCEADD Q_CAP..1
(-1500 4900);
FORCEPROP 1 LAST LOCATION PC599
J 0
(-1450 5000);
DISPLAY 0.489362 (-1450 5000);
PAINT SKYBLUE (-1450 5000);
FORCEPROP 0 LAST $SEC 1
J 0
(-1450 5025);
DISPLAY 0.680851 (-1450 5025);
PAINT MONO (-1450 5025);
DISPLAY INVISIBLE (-1450 5025);
FORCEPROP 0 LAST CDS_SEC 1
J 0
(-1450 5025);
DISPLAY 1.021277 (-1450 5025);
DISPLAY INVISIBLE (-1450 5025);
FORCEPROP 1 LASTPIN (-1500 5000) $PN 1
J 0
(-1490 4980);
DISPLAY 0.489362 (-1490 4980);
PAINT MONO (-1490 4980);
FORCEPROP 1 LASTPIN (-1500 4800) $PN 2
J 0
(-1490 4780);
DISPLAY 0.489362 (-1490 4780);
PAINT MONO (-1490 4780);
FORCEPROP 1 LAST TOLERANCE 10%
J 0
(-1450 4850);
DISPLAY 0.489362 (-1450 4850);
PAINT SKYBLUE (-1450 4850);
FORCEPROP 1 LAST VOLTAGE 25V
J 0
(-1450 4900);
DISPLAY 0.489362 (-1450 4900);
PAINT SKYBLUE (-1450 4900);
FORCEPROP 1 LAST VALUE 0.1UF
J 0
(-1450 4950);
DISPLAY 0.489362 (-1450 4950);
PAINT SKYBLUE (-1450 4950);
FORCEPROP 1 LAST PACK_TYPE 0402
J 0
(-1450 4700);
DISPLAY 0.489362 (-1450 4700);
PAINT SKYBLUE (-1450 4700);
FORCEPROP 1 LAST MATERIAL X7R
J 0
(-1450 4800);
DISPLAY 0.489362 (-1450 4800);
PAINT SKYBLUE (-1450 4800);
FORCEPROP 1 LAST PART_NUMBER CH4104K1B00
J 0
(-1450 4750);
DISPLAY 0.489362 (-1450 4750);
PAINT SKYBLUE (-1450 4750);
DISPLAY INVISIBLE (-1450 4750);
FORCEPROP 1 LAST PATH I79
J 0
(-1450 5050);
DISPLAY 0.978723 (-1450 5050);
PAINT WHITE (-1450 5050);
DISPLAY INVISIBLE (-1450 5050);
FORCEPROP 2 LAST CDS_LIB pure_quanta
J 0
(-1500 4900);
DISPLAY INVISIBLE (-1500 4900);
FORCEADD Q_RES..1
(-6950 1675);
FORCEPROP 1 LAST LOCATION PR359
J 0
(-6950 1725);
DISPLAY 0.489362 (-6950 1725);
PAINT SKYBLUE (-6950 1725);
FORCEPROP 0 LAST $SEC 1
J 0
(-6950 1750);
DISPLAY 0.680851 (-6950 1750);
PAINT MONO (-6950 1750);
DISPLAY INVISIBLE (-6950 1750);
FORCEPROP 0 LAST CDS_SEC 1
J 0
(-6950 1750);
DISPLAY 1.021277 (-6950 1750);
DISPLAY INVISIBLE (-6950 1750);
FORCEPROP 1 LASTPIN (-7050 1675) $PN 1
J 0
(-7038 1687);
DISPLAY 0.489362 (-7038 1687);
PAINT MONO (-7038 1687);
FORCEPROP 1 LASTPIN (-6850 1675) $PN 2
J 0
(-6888 1687);
DISPLAY 0.489362 (-6888 1687);
PAINT MONO (-6888 1687);
FORCEPROP 1 LAST WATTAGE 1/16W
J 0
(-6850 1575);
DISPLAY 0.489362 (-6850 1575);
PAINT SKYBLUE (-6850 1575);
FORCEPROP 1 LAST MATERIAL EMPTY
J 0
(-7250 1575);
DISPLAY 0.489362 (-7250 1575);
PAINT RED (-7250 1575);
FORCEPROP 1 LAST PACK_TYPE 0402LF
J 0
(-6850 1625);
DISPLAY 0.489362 (-6850 1625);
PAINT SKYBLUE (-6850 1625);
FORCEPROP 1 LAST VALUE 8.87K
J 2
(-7075 1700);
DISPLAY 0.489362 (-7075 1700);
PAINT SKYBLUE (-7075 1700);
FORCEPROP 1 LAST TOLERANCE 1%
J 0
(-6825 1700);
DISPLAY 0.489362 (-6825 1700);
PAINT SKYBLUE (-6825 1700);
FORCEPROP 1 LAST PART_NUMBER CS28872FB01
J 0
(-7250 1625);
DISPLAY 0.489362 (-7250 1625);
PAINT SKYBLUE (-7250 1625);
DISPLAY INVISIBLE (-7250 1625);
FORCEPROP 1 LAST PATH I8
J 0
(-7000 1825);
DISPLAY 0.978723 (-7000 1825);
PAINT WHITE (-7000 1825);
DISPLAY INVISIBLE (-7000 1825);
FORCEPROP 2 LAST CDS_LIB pure_quanta
J 0
(-6950 1675);
DISPLAY INVISIBLE (-6950 1675);
FORCEADD Q_CAP..1
(-1125 4900);
FORCEPROP 1 LAST LOCATION PC602_1
J 0
(-1075 5000);
DISPLAY 0.489362 (-1075 5000);
PAINT SKYBLUE (-1075 5000);
FORCEPROP 0 LAST $SEC 1
J 0
(-1075 5025);
DISPLAY 0.680851 (-1075 5025);
PAINT MONO (-1075 5025);
DISPLAY INVISIBLE (-1075 5025);
FORCEPROP 0 LAST CDS_SEC 1
J 0
(-1075 5025);
DISPLAY 1.021277 (-1075 5025);
DISPLAY INVISIBLE (-1075 5025);
FORCEPROP 1 LASTPIN (-1125 5000) $PN 1
J 0
(-1115 4980);
DISPLAY 0.489362 (-1115 4980);
PAINT MONO (-1115 4980);
FORCEPROP 1 LASTPIN (-1125 4800) $PN 2
J 0
(-1115 4780);
DISPLAY 0.489362 (-1115 4780);
PAINT MONO (-1115 4780);
FORCEPROP 1 LAST PACK_TYPE C0805
J 0
(-1075 4700);
DISPLAY 0.489362 (-1075 4700);
PAINT SKYBLUE (-1075 4700);
FORCEPROP 1 LAST MATERIAL X6S
J 0
(-1075 4800);
DISPLAY 0.489362 (-1075 4800);
PAINT SKYBLUE (-1075 4800);
FORCEPROP 1 LAST TOLERANCE 20%
J 0
(-1075 4850);
DISPLAY 0.489362 (-1075 4850);
PAINT SKYBLUE (-1075 4850);
FORCEPROP 1 LAST VALUE 22UF
J 0
(-1075 4950);
DISPLAY 0.489362 (-1075 4950);
PAINT SKYBLUE (-1075 4950);
FORCEPROP 1 LAST VOLTAGE 4V
J 0
(-1075 4900);
DISPLAY 0.489362 (-1075 4900);
PAINT SKYBLUE (-1075 4900);
FORCEPROP 1 LAST PART_NUMBER CH622KMEA03
J 0
(-1075 4750);
DISPLAY 0.489362 (-1075 4750);
PAINT SKYBLUE (-1075 4750);
DISPLAY INVISIBLE (-1075 4750);
FORCEPROP 1 LAST PATH I80
J 0
(-1075 5050);
DISPLAY 0.978723 (-1075 5050);
PAINT WHITE (-1075 5050);
DISPLAY INVISIBLE (-1075 5050);
FORCEPROP 2 LAST CDS_LIB pure_quanta
J 0
(-1125 4900);
DISPLAY INVISIBLE (-1125 4900);
FORCEADD UNIVERSAL_GND..1
(-350 4475);
FORCEPROP 3 LASTPIN (-350 4525) SIG_NAME GND\g
J 0
(-340 4535);
DISPLAY 0.659574 (-340 4535);
PAINT MONO (-340 4535);
DISPLAY INVISIBLE (-340 4535);
FORCEPROP 1 LAST PATH I81
J 0
(-275 4475);
DISPLAY 0.872340 (-275 4475);
PAINT AQUA (-275 4475);
DISPLAY INVISIBLE (-275 4475);
FORCEPROP 1 LAST HDL_POWER GND
J 1
(-325 4400);
DISPLAY 0.872340 (-325 4400);
PAINT GREEN (-325 4400);
DISPLAY INVISIBLE (-325 4400);
FORCEPROP 2 LAST CDS_LIB pure_quanta_power
J 0
(-350 4475);
DISPLAY INVISIBLE (-350 4475);
FORCEADD Q_RES..2
(-350 4875);
FORCEPROP 1 LAST LOCATION PR334
J 0
(-305 5000);
DISPLAY 0.489362 (-305 5000);
PAINT SKYBLUE (-305 5000);
FORCEPROP 0 LAST $SEC 1
J 0
(-300 5025);
DISPLAY 0.680851 (-300 5025);
PAINT MONO (-300 5025);
DISPLAY INVISIBLE (-300 5025);
FORCEPROP 0 LAST CDS_SEC 1
J 0
(-300 5025);
DISPLAY 1.021277 (-300 5025);
DISPLAY INVISIBLE (-300 5025);
FORCEPROP 1 LASTPIN (-350 4975) $PN 1
J 0
(-345 4937);
DISPLAY 0.787234 (-345 4937);
PAINT MONO (-345 4937);
DISPLAY INVISIBLE (-345 4937);
FORCEPROP 1 LASTPIN (-350 4775) $PN 2
J 0
(-345 4785);
DISPLAY 0.787234 (-345 4785);
PAINT MONO (-345 4785);
DISPLAY INVISIBLE (-345 4785);
FORCEPROP 1 LAST WATTAGE 1/16W
J 0
(-310 4850);
DISPLAY 0.489362 (-310 4850);
PAINT SKYBLUE (-310 4850);
FORCEPROP 1 LAST MATERIAL CHIP
J 0
(-310 4800);
DISPLAY 0.489362 (-310 4800);
PAINT SKYBLUE (-310 4800);
FORCEPROP 1 LAST TOLERANCE 1%
J 0
(-305 4900);
DISPLAY 0.489362 (-305 4900);
PAINT SKYBLUE (-305 4900);
FORCEPROP 1 LAST VALUE 1K
J 0
(-305 4950);
DISPLAY 0.489362 (-305 4950);
PAINT SKYBLUE (-305 4950);
FORCEPROP 1 LAST PACK_TYPE 0402LF
J 0
(-310 4700);
DISPLAY 0.489362 (-310 4700);
PAINT SKYBLUE (-310 4700);
FORCEPROP 1 LAST PART_NUMBER CS21002FB06
J 0
(-310 4750);
DISPLAY 0.489362 (-310 4750);
PAINT SKYBLUE (-310 4750);
DISPLAY INVISIBLE (-310 4750);
FORCEPROP 1 LAST PATH I82
J 0
(-300 5050);
DISPLAY 0.978723 (-300 5050);
PAINT WHITE (-300 5050);
DISPLAY INVISIBLE (-300 5050);
FORCEPROP 2 LAST CDS_LIB pure_quanta
J 0
(-350 4875);
DISPLAY INVISIBLE (-350 4875);
FORCEADD Q_CAP..1
(-675 4900);
FORCEPROP 1 LAST LOCATION PC604_1
J 0
(-625 5000);
DISPLAY 0.489362 (-625 5000);
PAINT SKYBLUE (-625 5000);
FORCEPROP 0 LAST $SEC 1
J 0
(-625 5025);
DISPLAY 0.680851 (-625 5025);
PAINT MONO (-625 5025);
DISPLAY INVISIBLE (-625 5025);
FORCEPROP 0 LAST CDS_SEC 1
J 0
(-625 5025);
DISPLAY 1.021277 (-625 5025);
DISPLAY INVISIBLE (-625 5025);
FORCEPROP 1 LASTPIN (-675 5000) $PN 1
J 0
(-665 4980);
DISPLAY 0.489362 (-665 4980);
PAINT MONO (-665 4980);
FORCEPROP 1 LASTPIN (-675 4800) $PN 2
J 0
(-665 4780);
DISPLAY 0.489362 (-665 4780);
PAINT MONO (-665 4780);
FORCEPROP 1 LAST PACK_TYPE C0805
J 0
(-625 4750);
DISPLAY 0.489362 (-625 4750);
PAINT SKYBLUE (-625 4750);
FORCEPROP 1 LAST MATERIAL X6S
J 0
(-625 4800);
DISPLAY 0.489362 (-625 4800);
PAINT SKYBLUE (-625 4800);
FORCEPROP 1 LAST TOLERANCE 20%
J 0
(-625 4850);
DISPLAY 0.489362 (-625 4850);
PAINT SKYBLUE (-625 4850);
FORCEPROP 1 LAST VALUE 22UF
J 0
(-625 4950);
DISPLAY 0.489362 (-625 4950);
PAINT SKYBLUE (-625 4950);
FORCEPROP 1 LAST VOLTAGE 4V
J 0
(-625 4900);
DISPLAY 0.489362 (-625 4900);
PAINT SKYBLUE (-625 4900);
FORCEPROP 1 LAST PART_NUMBER CH622KMEA03
J 0
(-625 4750);
DISPLAY 0.489362 (-625 4750);
PAINT SKYBLUE (-625 4750);
DISPLAY INVISIBLE (-625 4750);
FORCEPROP 1 LAST PATH I83
J 0
(-625 5050);
DISPLAY 0.978723 (-625 5050);
PAINT WHITE (-625 5050);
DISPLAY INVISIBLE (-625 5050);
FORCEPROP 2 LAST CDS_LIB pure_quanta
J 0
(-675 4900);
DISPLAY INVISIBLE (-675 4900);
FORCEADD VCC_CORE..1
(-350 5200);
FORCEPROP 3 LASTPIN (-350 5150) SIG_NAME PVDDCR_SOC_P0\g
J 0
(-340 5160);
DISPLAY 0.659574 (-340 5160);
PAINT MONO (-340 5160);
DISPLAY INVISIBLE (-340 5160);
FORCEPROP 1 LAST HDL_POWER PVDDCR_SOC_P0
J 1
(-350 5250);
DISPLAY 0.489362 (-350 5250);
PAINT GREEN (-350 5250);
FORCEPROP 1 LAST PATH I84
J 0
(-300 5225);
DISPLAY 0.872340 (-300 5225);
PAINT AQUA (-300 5225);
DISPLAY INVISIBLE (-300 5225);
FORCEPROP 2 LAST CDS_LIB pure_quanta_power
J 0
(-350 5200);
DISPLAY INVISIBLE (-350 5200);
FORCEADD Q_CAP..1
(-4500 1800);
FORCEPROP 1 LAST LOCATION PC187
J 0
(-4450 1900);
DISPLAY 0.489362 (-4450 1900);
PAINT SKYBLUE (-4450 1900);
FORCEPROP 0 LAST $SEC 1
J 0
(-4450 1950);
DISPLAY 0.680851 (-4450 1950);
PAINT MONO (-4450 1950);
DISPLAY INVISIBLE (-4450 1950);
FORCEPROP 0 LAST CDS_SEC 1
J 0
(-4450 1950);
DISPLAY 1.021277 (-4450 1950);
DISPLAY INVISIBLE (-4450 1950);
FORCEPROP 1 LASTPIN (-4500 1900) $PN 1
J 0
(-4490 1880);
DISPLAY 0.489362 (-4490 1880);
PAINT MONO (-4490 1880);
FORCEPROP 1 LASTPIN (-4500 1700) $PN 2
J 0
(-4490 1680);
DISPLAY 0.489362 (-4490 1680);
PAINT MONO (-4490 1680);
FORCEPROP 1 LAST TOLERANCE 10%
J 0
(-4450 1750);
DISPLAY 0.489362 (-4450 1750);
PAINT SKYBLUE (-4450 1750);
FORCEPROP 1 LAST PACK_TYPE C0402
J 0
(-4450 1600);
DISPLAY 0.489362 (-4450 1600);
PAINT SKYBLUE (-4450 1600);
FORCEPROP 1 LAST VOLTAGE 50V
J 0
(-4450 1800);
DISPLAY 0.489362 (-4450 1800);
PAINT SKYBLUE (-4450 1800);
FORCEPROP 1 LAST VALUE 560PF
J 0
(-4450 1850);
DISPLAY 0.489362 (-4450 1850);
PAINT SKYBLUE (-4450 1850);
FORCEPROP 1 LAST MATERIAL EMPTY
J 0
(-4450 1700);
DISPLAY 0.489362 (-4450 1700);
PAINT RED (-4450 1700);
FORCEPROP 1 LAST PART_NUMBER CH1566K1B09
J 0
(-4450 1650);
DISPLAY 0.489362 (-4450 1650);
PAINT SKYBLUE (-4450 1650);
DISPLAY INVISIBLE (-4450 1650);
FORCEPROP 1 LAST PATH I85
J 0
(-4450 1950);
DISPLAY 0.978723 (-4450 1950);
PAINT WHITE (-4450 1950);
DISPLAY INVISIBLE (-4450 1950);
FORCEPROP 2 LAST CDS_LIB pure_quanta
J 0
(-4500 1800);
DISPLAY INVISIBLE (-4500 1800);
FORCEADD ISL99390FRZTR5935..1
(-5800 1975);
FORCEPROP 1 LAST LOCATION PU50
J 0
(-6100 2850);
DISPLAY 0.489362 (-6100 2850);
PAINT SKYBLUE (-6100 2850);
FORCEPROP 0 LAST $SEC 1
J 0
(-6100 3000);
DISPLAY 0.680851 (-6100 3000);
PAINT MONO (-6100 3000);
DISPLAY INVISIBLE (-6100 3000);
FORCEPROP 0 LAST CDS_SEC 1
J 0
(-6100 3000);
DISPLAY 1.021277 (-6100 3000);
DISPLAY INVISIBLE (-6100 3000);
FORCEPROP 0 LASTPIN (-5400 1525) $PN 2
J 0
(-5390 1535);
DISPLAY 0.489362 (-5390 1535);
PAINT MONO (-5390 1535);
FORCEPROP 0 LASTPIN (-5400 2325) $PN 33
J 0
(-5390 2335);
DISPLAY 0.489362 (-5390 2335);
PAINT MONO (-5390 2335);
FORCEPROP 0 LASTPIN (-6250 1725) $PN 31
J 2
(-6260 1735);
DISPLAY 0.489362 (-6260 1735);
PAINT MONO (-6260 1735);
FORCEPROP 0 LASTPIN (-6250 2125) $PN 35
J 2
(-6260 2135);
DISPLAY 0.489362 (-6260 2135);
PAINT MONO (-6260 2135);
FORCEPROP 0 LASTPIN (-5400 1675) $PN 6
J 0
(-5390 1685);
DISPLAY 0.489362 (-5390 1685);
PAINT MONO (-5390 1685);
FORCEPROP 0 LASTPIN (-5400 1625) $PN 41
J 0
(-5390 1635);
DISPLAY 0.489362 (-5390 1635);
PAINT MONO (-5390 1635);
FORCEPROP 0 LASTPIN (-6250 1975) $PN 38
J 2
(-6260 1985);
DISPLAY 0.489362 (-6260 1985);
PAINT MONO (-6260 1985);
FORCEPROP 0 LASTPIN (-6250 1675) $PN 37
J 2
(-6260 1685);
DISPLAY 0.489362 (-6260 1685);
PAINT MONO (-6260 1685);
FORCEPROP 0 LASTPIN (-5400 1475) $PN 5
J 0
(-5390 1485);
DISPLAY 0.489362 (-5390 1485);
PAINT MONO (-5390 1485);
FORCEPROP 0 LASTPIN (-5400 1425) $PN 7_9-20_24
J 0
(-5390 1435);
DISPLAY 0.489362 (-5390 1435);
PAINT MONO (-5390 1435);
FORCEPROP 0 LASTPIN (-5400 1375) $PN 40
J 0
(-5390 1385);
DISPLAY 0.489362 (-5390 1385);
PAINT MONO (-5390 1385);
FORCEPROP 0 LASTPIN (-5400 2075) $PN 32
J 0
(-5390 2085);
DISPLAY 0.489362 (-5390 2085);
PAINT MONO (-5390 2085);
FORCEPROP 0 LASTPIN (-6250 2625) $PN 4
J 2
(-6260 2635);
DISPLAY 0.489362 (-6260 2635);
PAINT MONO (-6260 2635);
FORCEPROP 0 LASTPIN (-6250 1375) $PN 34
J 2
(-6260 1385);
DISPLAY 0.489362 (-6260 1385);
PAINT MONO (-6260 1385);
FORCEPROP 0 LASTPIN (-6250 1875) $PN 39
J 2
(-6260 1885);
DISPLAY 0.489362 (-6260 1885);
PAINT MONO (-6260 1885);
FORCEPROP 0 LASTPIN (-5400 1975) $PN 10_19
J 0
(-5390 1985);
DISPLAY 0.489362 (-5390 1985);
PAINT MONO (-5390 1985);
FORCEPROP 0 LASTPIN (-6250 1475) $PN 36
J 2
(-6260 1485);
DISPLAY 0.489362 (-6260 1485);
PAINT MONO (-6260 1485);
FORCEPROP 0 LASTPIN (-6250 2325) $PN 3
J 2
(-6260 2335);
DISPLAY 0.489362 (-6260 2335);
PAINT MONO (-6260 2335);
FORCEPROP 0 LASTPIN (-5400 2625) $PN 25_29
J 0
(-5390 2635);
DISPLAY 0.489362 (-5390 2635);
PAINT MONO (-5390 2635);
FORCEPROP 0 LASTPIN (-5400 2575) $PN 30
J 0
(-5390 2585);
DISPLAY 0.489362 (-5390 2585);
PAINT MONO (-5390 2585);
FORCEPROP 0 LASTPIN (-5400 1725) $PN 1
J 0
(-5390 1735);
DISPLAY 0.489362 (-5390 1735);
PAINT MONO (-5390 1735);
FORCEPROP 2 LAST VALUE ISL99390FRZ-TR5935
J 0
(-6100 2900);
DISPLAY 0.489362 (-6100 2900);
PAINT SKYBLUE (-6100 2900);
FORCEPROP 2 LAST PART_TYPE SMLF
J 0
(-6100 2950);
DISPLAY 1.021277 (-6100 2950);
FORCEPROP 1 LAST MATERIAL IC
J 0
(-6100 2700);
DISPLAY 0.489362 (-6100 2700);
PAINT SKYBLUE (-6100 2700);
FORCEPROP 1 LAST PART_NUMBER AL099390004
J 0
(-6100 2775);
DISPLAY 0.489362 (-6100 2775);
PAINT SKYBLUE (-6100 2775);
DISPLAY INVISIBLE (-6100 2775);
FORCEPROP 1 LAST PATH I86
J 0
(-5800 1975);
DISPLAY 0.723404 (-5800 1975);
PAINT GREEN (-5800 1975);
DISPLAY INVISIBLE (-5800 1975);
FORCEPROP 2 LAST CDS_LIB pure_quanta
J 0
(-5800 1975);
DISPLAY INVISIBLE (-5800 1975);
FORCEPROP 1 LAST NEEDS_NO_SIZE TRUE
J 0
(-5800 1975);
DISPLAY 0.723404 (-5800 1975);
PAINT GREEN (-5800 1975);
DISPLAY INVISIBLE (-5800 1975);
FORCEPROP 1 LAST CDS_LMAN_SYM_OUTLINE -300,700,250,-650
J 0
(-5800 1975);
DISPLAY 0.468085 (-5800 1975);
PAINT GREEN (-5800 1975);
DISPLAY INVISIBLE (-5800 1975);
FORCEADD Q_CAP..1
(-3550 5925);
FORCEPROP 1 LAST LOCATION PC8009
J 0
(-3500 6025);
DISPLAY 0.489362 (-3500 6025);
PAINT SKYBLUE (-3500 6025);
FORCEPROP 0 LAST $SEC 1
J 0
(-3500 6050);
DISPLAY 0.680851 (-3500 6050);
PAINT MONO (-3500 6050);
DISPLAY INVISIBLE (-3500 6050);
FORCEPROP 0 LAST CDS_SEC 1
J 0
(-3500 6050);
DISPLAY 0.680851 (-3500 6050);
DISPLAY INVISIBLE (-3500 6050);
FORCEPROP 1 LASTPIN (-3550 6025) $PN 1
J 0
(-3540 6005);
DISPLAY 0.787234 (-3540 6005);
PAINT MONO (-3540 6005);
FORCEPROP 1 LASTPIN (-3550 5825) $PN 2
J 0
(-3540 5805);
DISPLAY 0.787234 (-3540 5805);
PAINT MONO (-3540 5805);
FORCEPROP 1 LAST PACK_TYPE C0805
J 0
(-3500 5725);
DISPLAY 0.489362 (-3500 5725);
PAINT SKYBLUE (-3500 5725);
FORCEPROP 1 LAST MATERIAL X6S
J 0
(-3500 5825);
DISPLAY 0.489362 (-3500 5825);
PAINT SKYBLUE (-3500 5825);
FORCEPROP 1 LAST TOLERANCE 20%
J 0
(-3500 5875);
DISPLAY 0.489362 (-3500 5875);
PAINT SKYBLUE (-3500 5875);
FORCEPROP 1 LAST VOLTAGE 16V
J 0
(-3500 5925);
DISPLAY 0.489362 (-3500 5925);
PAINT SKYBLUE (-3500 5925);
FORCEPROP 1 LAST VALUE 22UF
J 0
(-3500 5975);
DISPLAY 0.489362 (-3500 5975);
PAINT SKYBLUE (-3500 5975);
FORCEPROP 1 LAST PART_NUMBER CH6223MEA01
J 0
(-3500 5775);
DISPLAY 0.489362 (-3500 5775);
PAINT SKYBLUE (-3500 5775);
DISPLAY INVISIBLE (-3500 5775);
FORCEPROP 1 LAST PATH I87
J 0
(-3500 6075);
DISPLAY 0.978723 (-3500 6075);
PAINT WHITE (-3500 6075);
DISPLAY INVISIBLE (-3500 6075);
FORCEPROP 2 LAST CDS_LIB pure_quanta
J 0
(-3550 5925);
DISPLAY INVISIBLE (-3550 5925);
FORCEADD Q_CAP..1
(-3075 2850);
FORCEPROP 1 LAST LOCATION PC8010
J 0
(-3025 2950);
DISPLAY 0.489362 (-3025 2950);
PAINT SKYBLUE (-3025 2950);
FORCEPROP 0 LAST $SEC 1
J 0
(-3025 2975);
DISPLAY 0.680851 (-3025 2975);
PAINT MONO (-3025 2975);
DISPLAY INVISIBLE (-3025 2975);
FORCEPROP 0 LAST CDS_SEC 1
J 0
(-3025 2975);
DISPLAY 0.680851 (-3025 2975);
DISPLAY INVISIBLE (-3025 2975);
FORCEPROP 1 LASTPIN (-3075 2950) $PN 1
J 0
(-3065 2930);
DISPLAY 0.787234 (-3065 2930);
PAINT MONO (-3065 2930);
FORCEPROP 1 LASTPIN (-3075 2750) $PN 2
J 0
(-3065 2730);
DISPLAY 0.787234 (-3065 2730);
PAINT MONO (-3065 2730);
FORCEPROP 1 LAST TOLERANCE 20%
J 0
(-3025 2800);
DISPLAY 0.489362 (-3025 2800);
PAINT SKYBLUE (-3025 2800);
FORCEPROP 1 LAST PACK_TYPE C0805
J 0
(-3025 2650);
DISPLAY 0.489362 (-3025 2650);
PAINT SKYBLUE (-3025 2650);
FORCEPROP 1 LAST MATERIAL X6S
J 0
(-3025 2750);
DISPLAY 0.489362 (-3025 2750);
PAINT SKYBLUE (-3025 2750);
FORCEPROP 1 LAST VALUE 22UF
J 0
(-3025 2900);
DISPLAY 0.489362 (-3025 2900);
PAINT SKYBLUE (-3025 2900);
FORCEPROP 1 LAST VOLTAGE 16V
J 0
(-3025 2850);
DISPLAY 0.489362 (-3025 2850);
PAINT SKYBLUE (-3025 2850);
FORCEPROP 1 LAST PART_NUMBER CH6223MEA01
J 0
(-3025 2700);
DISPLAY 0.489362 (-3025 2700);
PAINT SKYBLUE (-3025 2700);
DISPLAY INVISIBLE (-3025 2700);
FORCEPROP 1 LAST PATH I88
J 0
(-3025 3000);
DISPLAY 0.978723 (-3025 3000);
PAINT WHITE (-3025 3000);
DISPLAY INVISIBLE (-3025 3000);
FORCEPROP 2 LAST CDS_LIB pure_quanta
J 0
(-3075 2850);
DISPLAY INVISIBLE (-3075 2850);
FORCEADD UNIVERSAL_GND..1
(-7300 2125);
FORCEPROP 3 LASTPIN (-7300 2175) SIG_NAME GND\g
J 0
(-7290 2185);
DISPLAY 0.659574 (-7290 2185);
PAINT MONO (-7290 2185);
DISPLAY INVISIBLE (-7290 2185);
FORCEPROP 1 LAST PATH I9
J 0
(-7225 2125);
DISPLAY 0.872340 (-7225 2125);
PAINT AQUA (-7225 2125);
DISPLAY INVISIBLE (-7225 2125);
FORCEPROP 1 LAST HDL_POWER GND
J 1
(-7275 2050);
DISPLAY 0.872340 (-7275 2050);
PAINT GREEN (-7275 2050);
DISPLAY INVISIBLE (-7275 2050);
FORCEPROP 2 LAST CDS_LIB pure_quanta_power
J 0
(-7300 2125);
DISPLAY INVISIBLE (-7300 2125);
FORCEADD QUANTA_TITLE_BLOCK_C..1
(0 0);
FORCEPROP 0 LAST CDS_CON_LAST_MODIFIED Thu Sep 14 16:12:18 2023
J 0
(-1885 15);
DISPLAY INVISIBLE (-1885 15);
FORCEPROP 1 LAST CUSTOM_TXT_CDS <CON_LAST_MODIFIED>
J 0
(-1885 15);
DISPLAY 0.978723 (-1885 15);
FORCEPROP 2 LAST CUSTOM_TXT_CDS <XR_PAGE_TITLE>
J 0
(-7890 5250);
DISPLAY 0.638298 (-7890 5250);
PAINT PINK (-7890 5250);
DISPLAY INVISIBLE (-7890 5250);
FORCEPROP 1 LAST CUSTOM_TXT_CDS <NAME_2>
J 0
(-3175 50);
FORCEPROP 1 LAST CUSTOM_TXT_CDS <NAME_1>
J 0
(-3175 175);
FORCEPROP 1 LAST CUSTOM_TXT_CDS <Q_NUMBER>
J 0
(-1403 103);
DISPLAY 1.212766 (-1403 103);
FORCEPROP 1 LAST CUSTOM_TXT_CDS <Q_PROJ>
J 0
(-2382 102);
DISPLAY 1.212766 (-2382 102);
FORCEPROP 1 LAST CUSTOM_TXT_CDS <Q_REV>
J 0
(-184 103);
DISPLAY 1.212766 (-184 103);
FORCEPROP 1 LAST CUSTOM_TXT_CDS <CON_PAGE_NUM> OF <CON_TOTAL_PAGES>
J 0
(-446 18);
DISPLAY 0.978723 (-446 18);
FORCEPROP 1 LAST Q_TITLE PVDDCR_SOC_P0 VR PHASE 1&2
J 0
(-9325 50);
DISPLAY 2.446809 (-9325 50);
PAINT GREEN (-9325 50);
FORCEPROP 1 LAST COMMENT_BODY TRUE
J 0
(12 -13);
DISPLAY 0.978723 (12 -13);
PAINT GREEN (12 -13);
DISPLAY INVISIBLE (12 -13);
FORCEPROP 1 LAST Q_DEPT BU9
J 1
(-3763 49);
DISPLAY 1.957447 (-3763 49);
PAINT GREEN (-3763 49);
DISPLAY INVISIBLE (-3763 49);
FORCEPROP 2 LAST CDS_XR_PAGE_TITLE CR-198 : @T6G_MB_LIB.T6G(SCH_1):PAGE198
J 0
(-7890 5250);
DISPLAY 0.638298 (-7890 5250);
PAINT PINK (-7890 5250);
DISPLAY INVISIBLE (-7890 5250);
FORCEPROP 2 LAST PAGE_BORDER TRUE
J 0
(-7890 5250);
DISPLAY 0.638298 (-7890 5250);
PAINT PINK (-7890 5250);
DISPLAY INVISIBLE (-7890 5250);
FORCEPROP 1 LAST CDS_LMAN_SYM_OUTLINE -9475,6775,100,-125
J 0
(0 0);
DISPLAY 0.468085 (0 0);
PAINT GREEN (0 0);
DISPLAY INVISIBLE (0 0);
FORCEPROP 2 LAST CDS_LIB pure_quanta
J 0
(0 0);
DISPLAY INVISIBLE (0 0);
FORCEADD DNS..1
(-4525 1800);
PAINT RED (-4525 1800);
FORCEPROP 1 LAST COMMENT_BODY TRUE
R 1
J 0
(-4450 1575);
DISPLAY 0.872340 (-4450 1575);
PAINT GREEN (-4450 1575);
DISPLAY INVISIBLE (-4450 1575);
FORCEPROP 2 LAST CDS_LIB mstr_misc
J 0
(-4525 1800);
DISPLAY INVISIBLE (-4525 1800);
FORCEADD DNS..1
(-1625 3225);
PAINT RED (-1625 3225);
FORCEPROP 1 LAST COMMENT_BODY TRUE
R 1
J 0
(-1550 3000);
DISPLAY 0.872340 (-1550 3000);
PAINT GREEN (-1550 3000);
DISPLAY INVISIBLE (-1550 3000);
FORCEPROP 2 LAST CDS_LIB mstr_misc
J 0
(-1625 3225);
DISPLAY INVISIBLE (-1625 3225);
FORCEADD DNS..1
(-4475 4400);
PAINT RED (-4475 4400);
FORCEPROP 1 LAST COMMENT_BODY TRUE
R 1
J 0
(-4400 4175);
DISPLAY 0.872340 (-4400 4175);
PAINT GREEN (-4400 4175);
DISPLAY INVISIBLE (-4400 4175);
FORCEPROP 2 LAST CDS_LIB mstr_misc
J 0
(-4475 4400);
DISPLAY INVISIBLE (-4475 4400);
FORCEADD DNS..1
(-4525 1300);
PAINT RED (-4525 1300);
FORCEPROP 1 LAST COMMENT_BODY TRUE
R 1
J 0
(-4450 1075);
DISPLAY 0.872340 (-4450 1075);
PAINT GREEN (-4450 1075);
DISPLAY INVISIBLE (-4450 1075);
FORCEPROP 2 LAST CDS_LIB mstr_misc
J 0
(-4525 1300);
DISPLAY INVISIBLE (-4525 1300);
FORCEADD DNS..1
(-6950 1650);
PAINT RED (-6950 1650);
FORCEPROP 1 LAST COMMENT_BODY TRUE
R 1
J 0
(-6875 1425);
DISPLAY 0.872340 (-6875 1425);
PAINT GREEN (-6875 1425);
DISPLAY INVISIBLE (-6875 1425);
FORCEPROP 2 LAST CDS_LIB mstr_misc
J 0
(-6950 1650);
DISPLAY INVISIBLE (-6950 1650);
FORCEADD DNS..1
(-4450 4825);
PAINT RED (-4450 4825);
FORCEPROP 1 LAST COMMENT_BODY TRUE
R 1
J 0
(-4375 4600);
DISPLAY 0.872340 (-4375 4600);
PAINT GREEN (-4375 4600);
DISPLAY INVISIBLE (-4375 4600);
FORCEPROP 2 LAST CDS_LIB mstr_misc
J 0
(-4450 4825);
DISPLAY INVISIBLE (-4450 4825);
FORCEADD DNS..1
(-7000 4750);
PAINT RED (-7000 4750);
FORCEPROP 1 LAST COMMENT_BODY TRUE
R 1
J 0
(-6925 4525);
DISPLAY 0.872340 (-6925 4525);
PAINT GREEN (-6925 4525);
DISPLAY INVISIBLE (-6925 4525);
FORCEPROP 2 LAST CDS_LIB mstr_misc
J 0
(-7000 4750);
DISPLAY INVISIBLE (-7000 4750);
WIRE 16 -1 (-6950 2750)(-6950 2650);
WIRE 16 -1 (-4500 1200)(-4500 1125);
WIRE 16 -1 (-4475 4275)(-4475 4175);
WIRE 16 -1 (-7650 4700)(-7650 4575);
WIRE 16 -1 (-7625 1600)(-7625 1475);
WIRE 16 -1 (-7100 4775)(-7325 4775);
WIRE 16 -1 (-7325 4775)(-7325 4650);
WIRE 16 -1 (-7325 5325)(-7325 5275);
WIRE 16 -1 (-6975 5825)(-6975 5725);
WIRE 16 -1 (-7050 1675)(-7300 1675);
WIRE 16 -1 (-7300 1675)(-7300 1550);
WIRE 16 -1 (-2375 5850)(-2375 5675);
WIRE 16 -1 (-7300 2225)(-7300 2175);
WIRE 16 -1 (-6600 2625)(-6600 3075);
WIRE 16 -1 (-6600 2625)(-6250 2625);
WIRE 16 -1 (-6600 3075)(-6950 3075);
WIRE 16 -1 (-6950 2950)(-6950 3075);
WIRE 16 -1 (-6950 3075)(-7300 3075);
WIRE 16 -1 (-7300 3200)(-7300 3075);
WIRE 16 -1 (-7300 2950)(-7300 3075);
WIRE 16 -1 (-5225 1525)(-5225 1475);
WIRE 16 -1 (-5225 1525)(-5400 1525);
WIRE 16 -1 (-5225 1425)(-5225 1475);
WIRE 16 -1 (-5400 1475)(-5225 1475);
WIRE 16 -1 (-5225 1375)(-5225 1425);
WIRE 16 -1 (-5400 1425)(-5225 1425);
WIRE 16 -1 (-5225 1325)(-5225 1375);
WIRE 16 -1 (-5400 1375)(-5225 1375);
WIRE 16 -1 (-6625 5725)(-6625 6150);
WIRE 16 -1 (-6625 5725)(-6275 5725);
WIRE 16 -1 (-6625 6150)(-6975 6150);
WIRE 16 -1 (-6975 6150)(-7325 6150);
WIRE 16 -1 (-6975 6025)(-6975 6150);
WIRE 16 -1 (-7325 6275)(-7325 6150);
WIRE 16 -1 (-7325 6025)(-7325 6150);
WIRE 16 -1 (-5250 4625)(-5425 4625);
WIRE 16 -1 (-5250 4625)(-5250 4575);
WIRE 16 -1 (-5250 4525)(-5250 4575);
WIRE 16 -1 (-5425 4575)(-5250 4575);
WIRE 16 -1 (-5250 4475)(-5250 4525);
WIRE 16 -1 (-5425 4525)(-5250 4525);
WIRE 16 -1 (-5250 4400)(-5250 4475);
WIRE 16 -1 (-5425 4475)(-5250 4475);
WIRE 16 -1 (-5150 2775)(-5150 2650);
WIRE 16 -1 (-5150 2650)(-4775 2650);
WIRE 16 -1 (-4775 2650)(-4450 2650);
WIRE 16 -1 (-4775 2775)(-4775 2650);
WIRE 16 -1 (-4450 2650)(-4125 2650);
WIRE 16 -1 (-4450 2775)(-4450 2650);
WIRE 16 -1 (-4125 2650)(-3800 2650);
WIRE 16 -1 (-4125 2775)(-4125 2650);
WIRE 16 -1 (-3400 2650)(-3800 2650);
WIRE 16 -1 (-3800 2775)(-3800 2650);
WIRE 16 -1 (-3075 2650)(-3400 2650);
WIRE 16 -1 (-3400 2775)(-3400 2650);
WIRE 16 -1 (-3400 2650)(-3400 2600);
WIRE 16 -1 (-3075 2750)(-3075 2650);
WIRE 16 -1 (-5300 3050)(-5300 2625);
WIRE 16 -1 (-5300 3050)(-5150 3050);
WIRE 16 -1 (-5300 2625)(-5300 2575);
WIRE 16 -1 (-5400 2625)(-5300 2625);
WIRE 16 -1 (-5300 2575)(-5400 2575);
WIRE 16 -1 (-5150 3050)(-4775 3050);
WIRE 16 -1 (-5150 3050)(-5150 2975);
WIRE 16 -1 (-4775 3050)(-4450 3050);
WIRE 16 -1 (-4775 2975)(-4775 3050);
WIRE 16 -1 (-4450 3050)(-4125 3050);
WIRE 16 -1 (-4450 2975)(-4450 3050);
WIRE 16 -1 (-4125 3050)(-3800 3050);
WIRE 16 -1 (-4125 3050)(-4125 2975);
WIRE 16 -1 (-3400 3050)(-3800 3050);
WIRE 16 -1 (-3800 3050)(-3800 2975);
WIRE 16 -1 (-3400 3100)(-3400 3050);
WIRE 16 -1 (-3400 3050)(-3075 3050);
WIRE 16 -1 (-3400 2975)(-3400 3050);
WIRE 16 -1 (-3075 3050)(-3075 2950);
WIRE 16 -1 (-1425 1700)(-1425 1575);
WIRE 16 -1 (-1000 1575)(-1425 1575);
WIRE 16 -1 (-1000 1700)(-1000 1575);
WIRE 16 -1 (-1000 1500)(-1000 1575);
WIRE 16 -1 (-1775 1975)(-1425 1975);
WIRE 16 -1 (-1775 1975)(-1775 975);
WIRE 16 -1 (-2425 1975)(-1775 1975);
WIRE 16 -1 (-1425 1975)(-1000 1975);
WIRE 16 -1 (-1425 1975)(-1425 1900);
WIRE 16 -1 (-1000 2075)(-1000 1975);
WIRE 16 -1 (-1000 1975)(-1000 1900);
WIRE 16 -1 (-1775 975)(-3925 975);
WIRE 16 -1 (-1625 3150)(-1625 3000);
WIRE 16 -1 (-1275 3000)(-1625 3000);
WIRE 16 -1 (-950 3000)(-1275 3000);
WIRE 16 -1 (-1275 3150)(-1275 3000);
WIRE 16 -1 (-950 3150)(-950 3000);
WIRE 16 -1 (-950 2950)(-950 3000);
WIRE 16 -1 (-1275 3350)(-1275 3450);
WIRE 16 -1 (-950 3450)(-1275 3450);
WIRE 16 -1 (-1625 3450)(-1275 3450);
WIRE 16 -1 (-1625 3350)(-1625 3450);
WIRE 16 -1 (-950 3450)(-950 3475);
WIRE 16 -1 (-950 3350)(-950 3450);
WIRE 16 -1 (-5225 5825)(-5225 5700);
WIRE 16 -1 (-5225 5700)(-4900 5700);
WIRE 16 -1 (-4900 5700)(-4575 5700);
WIRE 16 -1 (-4900 5825)(-4900 5700);
WIRE 16 -1 (-4575 5700)(-4250 5700);
WIRE 16 -1 (-4575 5825)(-4575 5700);
WIRE 16 -1 (-4025 5700)(-4250 5700);
WIRE 16 -1 (-4250 5825)(-4250 5700);
WIRE 16 -1 (-3800 5700)(-4025 5700);
WIRE 16 -1 (-4025 5825)(-4025 5700);
WIRE 16 -1 (-3800 5700)(-3675 5700);
WIRE 16 -1 (-3800 5700)(-3800 5825);
WIRE 16 -1 (-3550 5700)(-3675 5700);
WIRE 16 -1 (-3675 5650)(-3675 5700);
WIRE 16 -1 (-3225 5700)(-3550 5700);
WIRE 16 -1 (-3550 5825)(-3550 5700);
WIRE 16 -1 (-3225 5825)(-3225 5700);
WIRE 16 -1 (-5325 6100)(-5325 5725);
WIRE 16 -1 (-5325 6100)(-5225 6100);
WIRE 16 -1 (-5325 5725)(-5325 5675);
WIRE 16 -1 (-5425 5725)(-5325 5725);
WIRE 16 -1 (-5325 5675)(-5425 5675);
WIRE 16 -1 (-5225 6100)(-4900 6100);
WIRE 16 -1 (-5225 6025)(-5225 6100);
WIRE 16 -1 (-4900 6100)(-4575 6100);
WIRE 16 -1 (-4900 6025)(-4900 6100);
WIRE 16 -1 (-4575 6100)(-4250 6100);
WIRE 16 -1 (-4575 6025)(-4575 6100);
WIRE 16 -1 (-4250 6100)(-4025 6100);
WIRE 16 -1 (-4250 6100)(-4250 6025);
WIRE 16 -1 (-3800 6100)(-4025 6100);
WIRE 16 -1 (-4025 6100)(-4025 6025);
WIRE 16 -1 (-3800 6100)(-3675 6100);
WIRE 16 -1 (-3800 6025)(-3800 6100);
WIRE 16 -1 (-3675 6150)(-3675 6100);
WIRE 16 -1 (-3550 6100)(-3675 6100);
WIRE 16 -1 (-3225 6100)(-3550 6100);
WIRE 16 -1 (-3550 6100)(-3550 6025);
WIRE 16 -1 (-2875 6100)(-3225 6100);
WIRE 16 -1 (-3225 6025)(-3225 6100);
WIRE 16 -1 (-2025 4725)(-2025 4825);
WIRE 16 -1 (-2025 4825)(-2500 4825);
WIRE 16 -1 (-2375 6150)(-2375 6100);
WIRE 16 -1 (-2375 6100)(-2375 6050);
WIRE 16 -1 (-2375 6100)(-2675 6100);
WIRE 16 -1 (-1500 4675)(-1125 4675);
WIRE 16 -1 (-1500 4675)(-1500 4800);
WIRE 16 -1 (-675 4675)(-1125 4675);
WIRE 16 -1 (-1125 4800)(-1125 4675);
WIRE 16 -1 (-350 4675)(-675 4675);
WIRE 16 -1 (-675 4800)(-675 4675);
WIRE 16 -1 (-350 4775)(-350 4675);
WIRE 16 -1 (-350 4525)(-350 4675);
WIRE 16 -1 (-1775 5075)(-1500 5075);
WIRE 16 -1 (-2500 5075)(-1775 5075);
WIRE 16 -1 (-1775 5075)(-1775 3900);
WIRE 16 -1 (-1125 5075)(-1500 5075);
WIRE 16 -1 (-1500 5000)(-1500 5075);
WIRE 16 -1 (-675 5075)(-1125 5075);
WIRE 16 -1 (-1125 5075)(-1125 5000);
WIRE 16 -1 (-1775 3900)(-3900 3900);
WIRE 16 -1 (-350 5075)(-675 5075);
WIRE 16 -1 (-675 5075)(-675 5000);
WIRE 16 -1 (-350 5150)(-350 5075);
WIRE 16 -1 (-350 5075)(-350 4975);
WIRE 16 -1 (-6275 5075)(-6925 5075);
FORCEPROP 2 LAST SIG_NAME PVDDCR_SOC_P0_IMON1
J 2
(-6335 5085);
DISPLAY 0.489362 (-6335 5085);
WIRE 16 -1 (-7325 5600)(-6825 5600);
WIRE 16 -1 (-7325 5825)(-7325 5600);
WIRE 16 -1 (-7325 5600)(-7325 5525);
WIRE 16 -1 (-6825 5600)(-6825 5425);
FORCEPROP 2 LAST SIG_NAME PVDDCR_SOC_P0_VCC1
J 2
(-6335 5435);
DISPLAY 0.489362 (-6335 5435);
FORCEPROP 2 LASTPROP $XRERR UNIQUE?
J 0
(-6575 5435);
DISPLAY 0.638298 (-6575 5435);
PAINT MONO (-6575 5435);
DISPLAY INVISIBLE (-6575 5435);
WIRE 16 -1 (-6825 5425)(-6275 5425);
WIRE 16 -1 (-6825 5425)(-6825 5225);
WIRE 16 -1 (-6825 5225)(-6275 5225);
WIRE 16 -1 (-3675 5200)(-3675 5175);
WIRE 16 -1 (-3675 5175)(-5425 5175);
FORCEPROP 2 LAST SIG_NAME SW_PVDDCR_SOC_P0_PH1
J 0
(-5335 5185);
DISPLAY 0.489362 (-5335 5185);
FORCEPROP 2 LASTPROP $XRERR UNIQUE?
J 0
(-5575 5185);
DISPLAY 0.638298 (-5575 5185);
PAINT MONO (-5575 5185);
DISPLAY INVISIBLE (-5575 5185);
WIRE 16 -1 (-3300 5075)(-4475 5075);
WIRE 16 -1 (-4475 5075)(-4475 4925);
WIRE 16 -1 (-5425 5075)(-4475 5075);
FORCEPROP 2 LAST SIG_NAME SW_PVDDCR_SOC_P0_SW1
J 0
(-5335 5085);
DISPLAY 0.489362 (-5335 5085);
FORCEPROP 2 LASTPROP $XRERR UNIQUE?
J 0
(-5575 5085);
DISPLAY 0.638298 (-5575 5085);
PAINT MONO (-5575 5085);
DISPLAY INVISIBLE (-5575 5085);
WIRE 16 -1 (-5425 5425)(-4625 5425);
FORCEPROP 2 LAST SIG_NAME SW_PVDDCR_SOC_P0_BOOT1
J 0
(-5335 5435);
DISPLAY 0.489362 (-5335 5435);
FORCEPROP 2 LASTPROP $XRERR UNIQUE?
J 0
(-5575 5435);
DISPLAY 0.638298 (-5575 5435);
PAINT MONO (-5575 5435);
DISPLAY INVISIBLE (-5575 5435);
WIRE 16 -1 (-5425 4825)(-4700 4825);
WIRE 16 -1 (-4700 3900)(-4700 4825);
WIRE 16 -1 (-4100 3900)(-4700 3900);
FORCEPROP 2 LAST SIG_NAME PVDDCR_SOC_P0_VOS1
J 0
(-5335 4850);
DISPLAY 0.489362 (-5335 4850);
FORCEPROP 2 LASTPROP $XRERR UNIQUE?
J 0
(-5575 4850);
DISPLAY 0.638298 (-5575 4850);
PAINT MONO (-5575 4850);
DISPLAY INVISIBLE (-5575 4850);
WIRE 16 -1 (-4475 4725)(-4475 4475);
FORCEPROP 2 LAST SIG_NAME SW_PVDDCR_SOC_P0_SW1_RC
J 0
(-4435 4560);
DISPLAY 0.489362 (-4435 4560);
FORCEPROP 2 LASTPROP $XRERR UNIQUE?
J 0
(-4675 4560);
DISPLAY 0.638298 (-4675 4560);
PAINT MONO (-4675 4560);
DISPLAY INVISIBLE (-4675 4560);
WIRE 16 -1 (-3675 5425)(-3675 5400);
WIRE 16 -1 (-4425 5425)(-3675 5425);
FORCEPROP 2 LAST SIG_NAME SW_PVDDCR_SOC_P0_BOOT1_RC
J 2
(-3710 5435);
DISPLAY 0.489362 (-3710 5435);
FORCEPROP 2 LASTPROP $XRERR UNIQUE?
J 0
(-3950 5435);
DISPLAY 0.638298 (-3950 5435);
PAINT MONO (-3950 5435);
DISPLAY INVISIBLE (-3950 5435);
WIRE 16 -1 (-5400 2325)(-4575 2325);
FORCEPROP 2 LAST SIG_NAME SW_PVDDCR_SOC_P0_BOOT2
J 0
(-5285 2335);
DISPLAY 0.489362 (-5285 2335);
FORCEPROP 2 LASTPROP $XRERR UNIQUE?
J 0
(-5525 2335);
DISPLAY 0.638298 (-5525 2335);
PAINT MONO (-5525 2335);
DISPLAY INVISIBLE (-5525 2335);
WIRE 16 -1 (-3575 2325)(-3575 2300);
WIRE 16 -1 (-4375 2325)(-3575 2325);
FORCEPROP 2 LAST SIG_NAME SW_PVDDCR_SOC_P0_BOOT2_RC
J 2
(-3610 2335);
DISPLAY 0.489362 (-3610 2335);
FORCEPROP 2 LASTPROP $XRERR UNIQUE?
J 0
(-3850 2335);
DISPLAY 0.638298 (-3850 2335);
PAINT MONO (-3850 2335);
DISPLAY INVISIBLE (-3850 2335);
WIRE 17 273 (-400 2700)(-400 3725);
WIRE 17 273 (-2000 2700)(-400 2700);
WIRE 17 273 (-400 3725)(-2000 3725);
WIRE 17 273 (-2000 3725)(-2000 2700);
WIRE 16 -1 (-7800 1875)(-7625 1875);
WIRE 16 -1 (-6250 1875)(-7625 1875);
FORCEPROP 2 LAST SIG_NAME PVDDCR_CPU0_P0_VCCS
J 2
(-6310 1885);
DISPLAY 0.489362 (-6310 1885);
WIRE 16 -1 (-7625 1800)(-7625 1875);
WIRE 16 -1 (-6800 2125)(-6250 2125);
WIRE 16 -1 (-6800 2325)(-6800 2125);
WIRE 16 -1 (-6800 2325)(-6250 2325);
WIRE 16 -1 (-6800 2500)(-6800 2325);
FORCEPROP 2 LAST SIG_NAME PVDDCR_SOC_P0_VCC2
J 2
(-6335 2335);
DISPLAY 0.489362 (-6335 2335);
FORCEPROP 2 LASTPROP $XRERR UNIQUE?
J 0
(-6575 2335);
DISPLAY 0.638298 (-6575 2335);
PAINT MONO (-6575 2335);
DISPLAY INVISIBLE (-6575 2335);
WIRE 16 -1 (-7300 2500)(-6800 2500);
WIRE 16 -1 (-7300 2750)(-7300 2500);
WIRE 16 -1 (-7300 2500)(-7300 2425);
WIRE 16 -1 (-3575 2100)(-3575 2075);
WIRE 16 -1 (-3575 2075)(-5400 2075);
FORCEPROP 2 LAST SIG_NAME SW_PVDDCR_SOC_P0_PH2
J 0
(-5285 2085);
DISPLAY 0.489362 (-5285 2085);
FORCEPROP 2 LASTPROP $XRERR UNIQUE?
J 0
(-5525 2085);
DISPLAY 0.638298 (-5525 2085);
PAINT MONO (-5525 2085);
DISPLAY INVISIBLE (-5525 2085);
WIRE 16 -1 (-4500 1975)(-3225 1975);
WIRE 16 -1 (-4500 1975)(-4500 1900);
WIRE 16 -1 (-5400 1975)(-4500 1975);
FORCEPROP 2 LAST SIG_NAME SW_PVDDCR_SOC_P0_SW2
J 0
(-5285 1985);
DISPLAY 0.489362 (-5285 1985);
FORCEPROP 2 LASTPROP $XRERR UNIQUE?
J 0
(-5525 1985);
DISPLAY 0.638298 (-5525 1985);
PAINT MONO (-5525 1985);
DISPLAY INVISIBLE (-5525 1985);
WIRE 16 -1 (-6250 1725)(-6700 1725);
FORCEPROP 2 LAST SIG_NAME NC_PVDDCR_SOC_P0_DNC2
J 2
(-6310 1735);
DISPLAY 0.489362 (-6310 1735);
FORCEPROP 2 LASTPROP $XRERR UNIQUE?
J 0
(-6940 1725);
DISPLAY 0.638298 (-6940 1725);
PAINT MONO (-6940 1725);
DISPLAY INVISIBLE (-6940 1725);
WIRE 16 -1 (-6850 1675)(-6250 1675);
FORCEPROP 2 LAST SIG_NAME PVDDCR_SOC_P0_LSET2
J 2
(-6310 1685);
DISPLAY 0.489362 (-6310 1685);
FORCEPROP 2 LASTPROP $XRERR UNIQUE?
J 0
(-6550 1685);
DISPLAY 0.638298 (-6550 1685);
PAINT MONO (-6550 1685);
DISPLAY INVISIBLE (-6550 1685);
WIRE 16 -1 (-6250 1975)(-6900 1975);
FORCEPROP 2 LAST SIG_NAME PVDDCR_SOC_P0_IMON2
J 2
(-6310 1985);
DISPLAY 0.489362 (-6310 1985);
WIRE 16 -1 (-3750 4825)(-3300 4825);
FORCEPROP 2 LAST SIG_NAME IND_SOC_P0_CPL2
J 0
(-3735 4835);
DISPLAY 0.489362 (-3735 4835);
WIRE 16 -1 (-2050 1725)(-2425 1725);
FORCEPROP 2 LAST SIG_NAME IND_SOC_P0_CPL2
J 0
(-2385 1735);
DISPLAY 0.489362 (-2385 1735);
WIRE 16 -1 (-3750 1725)(-3225 1725);
FORCEPROP 2 LAST SIG_NAME IND_SOC_P0_CPL3
J 0
(-3685 1735);
DISPLAY 0.489362 (-3685 1735);
WIRE 16 -1 (-5425 4775)(-4900 4775);
FORCEPROP 2 LAST SIG_NAME NC_PVDDCR_SOC_P0_GL1_1
J 0
(-5335 4785);
DISPLAY 0.489362 (-5335 4785);
FORCEPROP 2 LASTPROP $XRERR UNIQUE?
J 0
(-4870 4775);
DISPLAY 0.638298 (-4870 4775);
PAINT MONO (-4870 4775);
DISPLAY INVISIBLE (-4870 4775);
WIRE 16 -1 (-5425 4725)(-4900 4725);
FORCEPROP 2 LAST SIG_NAME NC_PVDDCR_SOC_P0_GL2_1
J 0
(-5335 4735);
DISPLAY 0.489362 (-5335 4735);
FORCEPROP 2 LASTPROP $XRERR UNIQUE?
J 0
(-4870 4725);
DISPLAY 0.638298 (-4870 4725);
PAINT MONO (-4870 4725);
DISPLAY INVISIBLE (-4870 4725);
WIRE 16 -1 (-6900 4775)(-6275 4775);
FORCEPROP 2 LAST SIG_NAME PVDDCR_SOC_P0_LSET1
J 2
(-6335 4785);
DISPLAY 0.489362 (-6335 4785);
FORCEPROP 2 LASTPROP $XRERR UNIQUE?
J 0
(-6575 4785);
DISPLAY 0.638298 (-6575 4785);
PAINT MONO (-6575 4785);
DISPLAY INVISIBLE (-6575 4785);
WIRE 16 -1 (-6275 4475)(-6875 4475);
FORCEPROP 2 LAST SIG_NAME PVDDCR_SOC_P0_PWM1
J 2
(-6335 4485);
DISPLAY 0.489362 (-6335 4485);
WIRE 16 -1 (-6275 4575)(-6900 4575);
FORCEPROP 2 LAST SIG_NAME PVDDCR_SOC_P0_TEMP1
J 2
(-6335 4585);
DISPLAY 0.489362 (-6335 4585);
WIRE 16 -1 (-6275 4825)(-6725 4825);
FORCEPROP 2 LAST SIG_NAME NC_PVDDCR_SOC_P0_DNC1
J 2
(-6335 4835);
DISPLAY 0.489362 (-6335 4835);
FORCEPROP 2 LASTPROP $XRERR UNIQUE?
J 0
(-6965 4825);
DISPLAY 0.638298 (-6965 4825);
PAINT MONO (-6965 4825);
DISPLAY INVISIBLE (-6965 4825);
WIRE 16 -1 (-7825 4975)(-7650 4975);
WIRE 16 -1 (-6275 4975)(-7650 4975);
FORCEPROP 2 LAST SIG_NAME PVDDCR_CPU0_P0_VCCS
J 2
(-6335 4985);
DISPLAY 0.489362 (-6335 4985);
WIRE 16 -1 (-7650 4900)(-7650 4975);
WIRE 16 -1 (-4500 1700)(-4500 1400);
FORCEPROP 2 LAST SIG_NAME SW_PVDDCR_SOC_P0_SW2_RC
J 0
(-4460 1510);
DISPLAY 0.489362 (-4460 1510);
FORCEPROP 2 LASTPROP $XRERR UNIQUE?
J 0
(-4700 1510);
DISPLAY 0.638298 (-4700 1510);
PAINT MONO (-4700 1510);
DISPLAY INVISIBLE (-4700 1510);
WIRE 16 -1 (-5400 1725)(-4700 1725);
WIRE 16 -1 (-4700 975)(-4700 1725);
WIRE 16 -1 (-4125 975)(-4700 975);
FORCEPROP 2 LAST SIG_NAME PVDDCR_SOC_P0_VOS2
J 0
(-5285 1750);
DISPLAY 0.489362 (-5285 1750);
FORCEPROP 2 LASTPROP $XRERR UNIQUE?
J 0
(-5525 1750);
DISPLAY 0.638298 (-5525 1750);
PAINT MONO (-5525 1750);
DISPLAY INVISIBLE (-5525 1750);
WIRE 16 -1 (-5400 1675)(-4875 1675);
FORCEPROP 2 LAST SIG_NAME NC_PVDDCR_SOC_P0_GL1_2
J 0
(-5285 1685);
DISPLAY 0.489362 (-5285 1685);
FORCEPROP 2 LASTPROP $XRERR UNIQUE?
J 0
(-4845 1675);
DISPLAY 0.638298 (-4845 1675);
PAINT MONO (-4845 1675);
DISPLAY INVISIBLE (-4845 1675);
WIRE 16 -1 (-5400 1625)(-4875 1625);
FORCEPROP 2 LAST SIG_NAME NC_PVDDCR_SOC_P0_GL2_2
J 0
(-5285 1635);
DISPLAY 0.489362 (-5285 1635);
FORCEPROP 2 LASTPROP $XRERR UNIQUE?
J 0
(-4845 1625);
DISPLAY 0.638298 (-4845 1625);
PAINT MONO (-4845 1625);
DISPLAY INVISIBLE (-4845 1625);
WIRE 16 -1 (-6250 1375)(-6850 1375);
FORCEPROP 2 LAST SIG_NAME PVDDCR_SOC_P0_PWM2
J 2
(-6310 1385);
DISPLAY 0.489362 (-6310 1385);
WIRE 16 -1 (-6250 1475)(-6875 1475);
FORCEPROP 2 LAST SIG_NAME PVDDCR_SOC_P0_TEMP1
J 2
(-6310 1485);
DISPLAY 0.489362 (-6310 1485);
DOT 1 (-4450 2650);
DOT 1 (-3225 6100);
DOT 1 (-4250 5700);
DOT 1 (-7625 1875);
DOT 1 (-7300 3075);
DOT 1 (-6800 2325);
DOT 1 (-6950 3075);
DOT 1 (-5225 1375);
DOT 1 (-5225 1425);
DOT 1 (-5225 1475);
DOT 1 (-4500 1975);
DOT 1 (-5300 2625);
DOT 1 (-5150 3050);
DOT 1 (-4775 2650);
DOT 1 (-4450 3050);
DOT 1 (-4125 2650);
DOT 1 (-4125 3050);
DOT 1 (-7650 4975);
DOT 1 (-7325 5600);
DOT 1 (-7325 6150);
DOT 1 (-6975 6150);
DOT 1 (-6825 5425);
DOT 1 (-5250 4475);
DOT 1 (-5250 4525);
DOT 1 (-5250 4575);
DOT 1 (-5325 5725);
DOT 1 (-4900 5700);
DOT 1 (-4575 6100);
DOT 1 (-3800 2650);
DOT 1 (-3800 3050);
DOT 1 (-1775 1975);
DOT 1 (-1425 1975);
DOT 1 (-1000 1575);
DOT 1 (-1000 1975);
DOT 1 (-1275 3000);
DOT 1 (-950 3000);
DOT 1 (-1275 3450);
DOT 1 (-950 3450);
DOT 1 (-3675 5700);
DOT 1 (-2375 6100);
DOT 1 (-1775 5075);
DOT 1 (-1500 5075);
DOT 1 (-1125 4675);
DOT 1 (-1125 5075);
DOT 1 (-675 4675);
DOT 1 (-350 4675);
DOT 1 (-675 5075);
DOT 1 (-350 5075);
DOT 1 (-4775 3050);
DOT 1 (-4475 5075);
DOT 1 (-7300 2500);
DOT 1 (-4250 6100);
DOT 1 (-4575 5700);
DOT 1 (-4025 5700);
DOT 1 (-3800 5700);
DOT 1 (-4900 6100);
DOT 1 (-5225 6100);
DOT 1 (-3800 6100);
DOT 1 (-3675 6100);
DOT 1 (-3550 5700);
DOT 1 (-4025 6100);
DOT 1 (-3550 6100);
DOT 1 (-3400 3050);
DOT 1 (-3400 2650);
FORCENOTE
PVDDCR_SOC_P0_PHASE1
(-6400 6475) 0;
DISPLAY LEFT (-6400 6475);
DISPLAY 1.595745 (-6400 6475);
PAINT WHITE (-6400 6475);
FORCENOTE
2ND=CV+15^0TZ01
(-2400 2025) 0;
DISPLAY LEFT (-2400 2025);
DISPLAY 0.638298 (-2400 2025);
PAINT WHITE (-2400 2025);
FORCENOTE
DCR=2-3,0.27M OHM
(-2400 2075) 0;
DISPLAY LEFT (-2400 2075);
DISPLAY 0.638298 (-2400 2075);
PAINT WHITE (-2400 2075);
FORCENOTE
DCR=1-4,0.105M OHM
(-2400 2125) 0;
DISPLAY LEFT (-2400 2125);
DISPLAY 0.638298 (-2400 2125);
PAINT WHITE (-2400 2125);
FORCENOTE
11.0*7.5*12.5
(-2400 2175) 0;
DISPLAY LEFT (-2400 2175);
DISPLAY 0.638298 (-2400 2175);
PAINT WHITE (-2400 2175);
FORCENOTE
PGL6303.151HLT
(-2400 2275) 0;
DISPLAY LEFT (-2400 2275);
DISPLAY 0.638298 (-2400 2275);
PAINT WHITE (-2400 2275);
FORCENOTE
ISAT:70A@100C
(-2400 2225) 0;
DISPLAY LEFT (-2400 2225);
DISPLAY 0.638298 (-2400 2225);
PAINT WHITE (-2400 2225);
FORCENOTE
ESR=4.5M OHM
(-1450 2925) 0;
DISPLAY LEFT (-1450 2925);
DISPLAY 0.638298 (-1450 2925);
PAINT WHITE (-1450 2925);
FORCENOTE
7.3*4.3*1.9
(-1450 2875) 0;
DISPLAY LEFT (-1450 2875);
DISPLAY 0.638298 (-1450 2875);
PAINT WHITE (-1450 2875);
FORCENOTE
2ND=CH747LM8822
(-1450 2825) 0;
DISPLAY LEFT (-1450 2825);
DISPLAY 0.638298 (-1450 2825);
PAINT WHITE (-1450 2825);
FORCENOTE
2ND=CVA50^0MZ07
(-2925 5825) 0;
DISPLAY LEFT (-2925 5825);
DISPLAY 0.638298 (-2925 5825);
PAINT WHITE (-2925 5825);
FORCENOTE
PG2292.500HLT
(-2925 6025) 0;
DISPLAY LEFT (-2925 6025);
DISPLAY 0.638298 (-2925 6025);
PAINT WHITE (-2925 6025);
FORCENOTE
DCR=0.09M OHM
(-2925 5875) 0;
DISPLAY LEFT (-2925 5875);
DISPLAY 0.638298 (-2925 5875);
PAINT WHITE (-2925 5875);
FORCENOTE
3RD=CVA50^0MZ08
(-2925 5775) 0;
DISPLAY LEFT (-2925 5775);
DISPLAY 0.638298 (-2925 5775);
PAINT WHITE (-2925 5775);
FORCENOTE
2ND=CV+15^0TZ01
(-2475 5125) 0;
DISPLAY LEFT (-2475 5125);
DISPLAY 0.638298 (-2475 5125);
PAINT WHITE (-2475 5125);
FORCENOTE
DCR=2-3,0.27M OHM
(-2475 5175) 0;
DISPLAY LEFT (-2475 5175);
DISPLAY 0.638298 (-2475 5175);
PAINT WHITE (-2475 5175);
FORCENOTE
DCR=1-4,0.105M OHM
(-2475 5225) 0;
DISPLAY LEFT (-2475 5225);
DISPLAY 0.638298 (-2475 5225);
PAINT WHITE (-2475 5225);
FORCENOTE
11.0*7.5*12.5
(-2475 5275) 0;
DISPLAY LEFT (-2475 5275);
DISPLAY 0.638298 (-2475 5275);
PAINT WHITE (-2475 5275);
FORCENOTE
PGL6303.151HLT
(-2475 5375) 0;
DISPLAY LEFT (-2475 5375);
DISPLAY 0.638298 (-2475 5375);
PAINT WHITE (-2475 5375);
FORCENOTE
ISAT:70A@100C
(-2475 5325) 0;
DISPLAY LEFT (-2475 5325);
DISPLAY 0.638298 (-2475 5325);
PAINT WHITE (-2475 5325);
FORCENOTE
3RD SOURCE:MPS BOM
(-9175 525) 0;
DISPLAY LEFT (-9175 525);
DISPLAY 1.021277 (-9175 525);
PAINT WHITE (-9175 525);
FORCENOTE
ISAT:70A@100C
(-2925 5975) 0;
DISPLAY LEFT (-2925 5975);
DISPLAY 0.638298 (-2925 5975);
PAINT WHITE (-2925 5975);
FORCENOTE
6.0*6.1*7.0
(-2925 5925) 0;
DISPLAY LEFT (-2925 5925);
DISPLAY 0.638298 (-2925 5925);
PAINT WHITE (-2925 5925);
FORCENOTE
ESR=10M OHM
(-3350 5650) 0;
DISPLAY LEFT (-3350 5650);
DISPLAY 0.638298 (-3350 5650);
PAINT WHITE (-3350 5650);
FORCENOTE
IRIPPLE:5.08A
(-3350 5600) 0;
DISPLAY LEFT (-3350 5600);
DISPLAY 0.638298 (-3350 5600);
PAINT WHITE (-3350 5600);
FORCENOTE
6.3*8
(-3350 5550) 0;
DISPLAY LEFT (-3350 5550);
DISPLAY 0.638298 (-3350 5550);
PAINT WHITE (-3350 5550);
FORCENOTE
2ND=CC72703MD39
(-3350 5500) 0;
DISPLAY LEFT (-3350 5500);
DISPLAY 0.638298 (-3350 5500);
PAINT WHITE (-3350 5500);
FORCENOTE
PVDDCR_SOC_P0_PHASE2
(-6375 3375) 0;
DISPLAY LEFT (-6375 3375);
DISPLAY 1.595745 (-6375 3375);
PAINT WHITE (-6375 3375);
FORCENOTE
PR360,PR361,PR366 = CS00002JB13
(-9175 375) 0;
DISPLAY LEFT (-9175 375);
DISPLAY 0.808511 (-9175 375);
PAINT WHITE (-9175 375);
FORCENOTE
PR362,PR363,PR367=EMPTY
(-9175 300) 0;
DISPLAY LEFT (-9175 300);
DISPLAY 0.808511 (-9175 300);
PAINT WHITE (-9175 300);
FORCENOTE
PC577_7,PC578_8,PC605_9=EMPTY
(-9175 225) 0;
DISPLAY LEFT (-9175 225);
DISPLAY 0.808511 (-9175 225);
PAINT WHITE (-9175 225);
FORCENOTE
PU49,PU50,PU51 = AL087000A03/MP87000GMJTH-C11D-Z
(-9175 450) 0;
DISPLAY LEFT (-9175 450);
DISPLAY 0.808511 (-9175 450);
PAINT WHITE (-9175 450);
FORCENOTE
PU49,PU50,PU51 = AL099390004/ISL99390FRZ-TR5935
(-9200 1300) 0;
DISPLAY LEFT (-9200 1300);
DISPLAY 0.808511 (-9200 1300);
PAINT WHITE (-9200 1300);
FORCENOTE
2ND SOURCE:INFENEON BOM
(-9200 1100) 0;
DISPLAY LEFT (-9200 1100);
DISPLAY 1.021277 (-9200 1100);
PAINT WHITE (-9200 1100);
FORCENOTE
PU49,PU50,PU51 = AL021590000/TDA21590
(-9200 1025) 0;
DISPLAY LEFT (-9200 1025);
DISPLAY 0.808511 (-9200 1025);
PAINT WHITE (-9200 1025);
FORCENOTE
PC577_7,PC578_8,PC605_9 = EMPTY
(-9200 725) 0;
DISPLAY LEFT (-9200 725);
DISPLAY 0.808511 (-9200 725);
PAINT WHITE (-9200 725);
FORCENOTE
PR362,PR363,PR367 = EMPTY
(-9200 800) 0;
DISPLAY LEFT (-9200 800);
DISPLAY 0.808511 (-9200 800);
PAINT WHITE (-9200 800);
FORCENOTE
PR358,PR359,PR365 = CS00002JB13
(-9200 875) 0;
DISPLAY LEFT (-9200 875);
DISPLAY 0.808511 (-9200 875);
PAINT WHITE (-9200 875);
FORCENOTE
PR360,PR361,PR366 = CS00002JB13
(-9200 950) 0;
DISPLAY LEFT (-9200 950);
DISPLAY 0.808511 (-9200 950);
PAINT WHITE (-9200 950);
FORCENOTE
MAIN SOURCE:RENESAS BOM
(-9200 1375) 0;
DISPLAY LEFT (-9200 1375);
DISPLAY 1.021277 (-9200 1375);
PAINT WHITE (-9200 1375);
FORCENOTE
BOM NOTE
(-9200 1475) 0;
DISPLAY LEFT (-9200 1475);
DISPLAY 1.595745 (-9200 1475);
PAINT WHITE (-9200 1475);
QUIT
